(kicad_sch
	(version 20250114)
	(generator "eeschema")
	(generator_version "9.0")
	(paper "A3")
	(title_block
		(title "LPDDR4 Test Board")
		(date "2024-02-12")
		(rev "1.1.5")
	)
	(text "Clock source"
		(exclude_from_sim no)
		(at 53.34 221.615 0)
		(effects
			(font
				(size 2.4892 2.4892)
				(thickness 0.4978)
				(bold yes)
			)
			(justify left bottom)
		)
	)
	(text "INTERFACES"
		(exclude_from_sim no)
		(at 66.675 26.035 0)
		(effects
			(font
				(size 2.4892 2.4892)
				(thickness 0.4978)
				(bold yes)
			)
			(justify left bottom)
		)
	)
	(text "CSI_B used \nfor config"
		(exclude_from_sim no)
		(at 120.015 128.905 0)
		(effects
			(font
				(size 1.27 1.27)
			)
			(justify left bottom)
		)
	)
	(text "ethernet.sch"
		(exclude_from_sim no)
		(at 158.115 90.17 90)
		(effects
			(font
				(size 1.27 1.27)
			)
			(justify left bottom)
		)
	)
	(text "LPDDR VREF"
		(exclude_from_sim no)
		(at 330.2 204.47 0)
		(effects
			(font
				(size 2.4892 2.4892)
				(thickness 0.4978)
				(bold yes)
			)
			(justify left bottom)
		)
	)
	(text "interfaces.sch\nHDMI"
		(exclude_from_sim no)
		(at 136.525 123.825 90)
		(effects
			(font
				(size 1.27 1.27)
			)
			(justify left bottom)
		)
	)
	(text "LPDDR4-TESTBED"
		(exclude_from_sim no)
		(at 326.39 26.035 0)
		(effects
			(font
				(size 2.4892 2.4892)
				(thickness 0.4978)
				(bold yes)
			)
			(justify left bottom)
		)
	)
	(text "UNUSED"
		(exclude_from_sim no)
		(at 198.12 205.105 0)
		(effects
			(font
				(size 2.4892 2.4892)
				(thickness 0.4978)
				(bold yes)
			)
			(justify left bottom)
		)
	)
	(text "INTERFACES"
		(exclude_from_sim no)
		(at 201.93 26.035 0)
		(effects
			(font
				(size 2.4892 2.4892)
				(thickness 0.4978)
				(bold yes)
			)
			(justify left bottom)
		)
	)
	(text "config-spi.sch"
		(exclude_from_sim no)
		(at 132.715 57.15 90)
		(effects
			(font
				(size 1.27 1.27)
			)
			(justify left bottom)
		)
	)
	(junction
		(at 343.535 224.79)
		(diameter 0)
		(color 0 0 0 0)
	)
	(junction
		(at 365.76 224.79)
		(diameter 0)
		(color 0 0 0 0)
	)
	(junction
		(at 355.6 224.79)
		(diameter 0)
		(color 0 0 0 0)
	)
	(junction
		(at 52.07 233.68)
		(diameter 0)
		(color 0 0 0 0)
	)
	(no_connect
		(at 37.465 145.415)
	)
	(no_connect
		(at 37.465 69.215)
	)
	(no_connect
		(at 382.27 120.015)
	)
	(no_connect
		(at 116.84 112.395)
	)
	(no_connect
		(at 302.895 59.055)
	)
	(no_connect
		(at 173.355 66.675)
	)
	(no_connect
		(at 173.355 69.215)
	)
	(no_connect
		(at 37.465 53.975)
	)
	(no_connect
		(at 302.895 76.835)
	)
	(no_connect
		(at 116.84 59.055)
	)
	(no_connect
		(at 37.465 165.735)
	)
	(no_connect
		(at 173.355 120.015)
	)
	(no_connect
		(at 116.84 142.875)
	)
	(no_connect
		(at 173.355 94.615)
	)
	(no_connect
		(at 302.895 43.815)
	)
	(no_connect
		(at 252.73 92.075)
	)
	(no_connect
		(at 116.84 104.775)
	)
	(no_connect
		(at 173.355 102.235)
	)
	(no_connect
		(at 252.73 64.135)
	)
	(no_connect
		(at 173.355 71.755)
	)
	(no_connect
		(at 116.84 125.095)
	)
	(no_connect
		(at 302.895 117.475)
	)
	(no_connect
		(at 173.355 41.275)
	)
	(no_connect
		(at 302.895 147.955)
	)
	(no_connect
		(at 191.77 262.89)
	)
	(no_connect
		(at 302.895 74.295)
	)
	(no_connect
		(at 302.895 89.535)
	)
	(no_connect
		(at 252.73 66.675)
	)
	(no_connect
		(at 302.895 84.455)
	)
	(no_connect
		(at 302.895 160.655)
	)
	(no_connect
		(at 116.84 41.275)
	)
	(no_connect
		(at 302.895 120.015)
	)
	(no_connect
		(at 116.84 61.595)
	)
	(no_connect
		(at 191.77 245.11)
	)
	(no_connect
		(at 116.84 158.115)
	)
	(no_connect
		(at 191.77 252.73)
	)
	(no_connect
		(at 302.895 66.675)
	)
	(no_connect
		(at 173.355 112.395)
	)
	(no_connect
		(at 116.84 64.135)
	)
	(no_connect
		(at 191.77 242.57)
	)
	(no_connect
		(at 116.84 97.155)
	)
	(no_connect
		(at 302.895 145.415)
	)
	(no_connect
		(at 116.84 81.915)
	)
	(no_connect
		(at 116.84 94.615)
	)
	(no_connect
		(at 37.465 142.875)
	)
	(no_connect
		(at 173.355 150.495)
	)
	(no_connect
		(at 116.84 135.255)
	)
	(no_connect
		(at 302.895 86.995)
	)
	(no_connect
		(at 37.465 46.355)
	)
	(no_connect
		(at 37.465 163.195)
	)
	(no_connect
		(at 252.73 94.615)
	)
	(no_connect
		(at 37.465 94.615)
	)
	(no_connect
		(at 37.465 43.815)
	)
	(no_connect
		(at 191.77 229.87)
	)
	(no_connect
		(at 302.895 114.935)
	)
	(no_connect
		(at 37.465 102.235)
	)
	(no_connect
		(at 252.73 112.395)
	)
	(no_connect
		(at 252.73 53.975)
	)
	(no_connect
		(at 37.465 41.275)
	)
	(no_connect
		(at 302.895 81.915)
	)
	(no_connect
		(at 173.355 140.335)
	)
	(no_connect
		(at 302.895 107.315)
	)
	(no_connect
		(at 116.84 66.675)
	)
	(no_connect
		(at 302.895 94.615)
	)
	(no_connect
		(at 302.895 163.195)
	)
	(no_connect
		(at 37.465 135.255)
	)
	(no_connect
		(at 116.84 155.575)
	)
	(no_connect
		(at 302.895 150.495)
	)
	(no_connect
		(at 252.73 46.355)
	)
	(no_connect
		(at 302.895 112.395)
	)
	(no_connect
		(at 116.84 74.295)
	)
	(no_connect
		(at 191.77 227.33)
	)
	(no_connect
		(at 116.84 132.715)
	)
	(no_connect
		(at 252.73 109.855)
	)
	(no_connect
		(at 302.895 92.075)
	)
	(no_connect
		(at 382.27 132.715)
	)
	(no_connect
		(at 173.355 127.635)
	)
	(no_connect
		(at 37.465 160.655)
	)
	(no_connect
		(at 191.77 250.19)
	)
	(no_connect
		(at 173.355 125.095)
	)
	(no_connect
		(at 252.73 122.555)
	)
	(no_connect
		(at 37.465 56.515)
	)
	(no_connect
		(at 191.77 255.27)
	)
	(no_connect
		(at 302.895 155.575)
	)
	(no_connect
		(at 302.895 165.735)
	)
	(no_connect
		(at 37.465 89.535)
	)
	(no_connect
		(at 173.355 46.355)
	)
	(no_connect
		(at 252.73 71.755)
	)
	(no_connect
		(at 302.895 104.775)
	)
	(no_connect
		(at 191.77 265.43)
	)
	(no_connect
		(at 382.27 135.255)
	)
	(no_connect
		(at 173.355 64.135)
	)
	(no_connect
		(at 302.895 53.975)
	)
	(no_connect
		(at 191.77 270.51)
	)
	(no_connect
		(at 252.73 43.815)
	)
	(no_connect
		(at 116.84 130.175)
	)
	(no_connect
		(at 252.73 48.895)
	)
	(no_connect
		(at 173.355 153.035)
	)
	(no_connect
		(at 302.895 79.375)
	)
	(no_connect
		(at 116.84 102.235)
	)
	(no_connect
		(at 173.355 165.735)
	)
	(no_connect
		(at 191.77 234.95)
	)
	(no_connect
		(at 173.355 43.815)
	)
	(no_connect
		(at 252.73 41.275)
	)
	(no_connect
		(at 191.77 257.81)
	)
	(no_connect
		(at 191.77 224.79)
	)
	(no_connect
		(at 116.84 79.375)
	)
	(no_connect
		(at 116.84 109.855)
	)
	(no_connect
		(at 173.355 97.155)
	)
	(no_connect
		(at 173.355 56.515)
	)
	(no_connect
		(at 37.465 99.695)
	)
	(no_connect
		(at 173.355 135.255)
	)
	(no_connect
		(at 191.77 222.25)
	)
	(no_connect
		(at 302.895 64.135)
	)
	(no_connect
		(at 37.465 48.895)
	)
	(no_connect
		(at 116.84 165.735)
	)
	(no_connect
		(at 37.465 107.315)
	)
	(no_connect
		(at 252.73 89.535)
	)
	(no_connect
		(at 252.73 56.515)
	)
	(no_connect
		(at 252.73 74.295)
	)
	(no_connect
		(at 116.84 145.415)
	)
	(no_connect
		(at 37.465 66.675)
	)
	(no_connect
		(at 252.73 51.435)
	)
	(no_connect
		(at 173.355 107.315)
	)
	(no_connect
		(at 173.355 117.475)
	)
	(no_connect
		(at 302.895 132.715)
	)
	(no_connect
		(at 302.895 109.855)
	)
	(no_connect
		(at 252.73 61.595)
	)
	(no_connect
		(at 252.73 59.055)
	)
	(no_connect
		(at 252.73 81.915)
	)
	(no_connect
		(at 302.895 122.555)
	)
	(no_connect
		(at 37.465 104.775)
	)
	(no_connect
		(at 116.84 107.315)
	)
	(no_connect
		(at 302.895 46.355)
	)
	(no_connect
		(at 116.84 140.335)
	)
	(no_connect
		(at 302.895 41.275)
	)
	(no_connect
		(at 191.77 247.65)
	)
	(no_connect
		(at 302.895 130.175)
	)
	(no_connect
		(at 173.355 53.975)
	)
	(no_connect
		(at 252.73 76.835)
	)
	(no_connect
		(at 191.77 240.03)
	)
	(no_connect
		(at 173.355 114.935)
	)
	(no_connect
		(at 116.84 86.995)
	)
	(no_connect
		(at 252.73 107.315)
	)
	(no_connect
		(at 252.73 99.695)
	)
	(no_connect
		(at 302.895 127.635)
	)
	(no_connect
		(at 116.84 137.795)
	)
	(no_connect
		(at 116.84 147.955)
	)
	(no_connect
		(at 191.77 217.17)
	)
	(no_connect
		(at 37.465 71.755)
	)
	(no_connect
		(at 191.77 219.71)
	)
	(no_connect
		(at 302.895 51.435)
	)
	(no_connect
		(at 116.84 84.455)
	)
	(no_connect
		(at 191.77 232.41)
	)
	(no_connect
		(at 302.895 97.155)
	)
	(no_connect
		(at 252.73 79.375)
	)
	(no_connect
		(at 302.895 102.235)
	)
	(no_connect
		(at 37.465 64.135)
	)
	(no_connect
		(at 382.27 99.695)
	)
	(no_connect
		(at 302.895 99.695)
	)
	(no_connect
		(at 116.84 76.835)
	)
	(no_connect
		(at 191.77 267.97)
	)
	(no_connect
		(at 302.895 153.035)
	)
	(no_connect
		(at 116.84 127.635)
	)
	(no_connect
		(at 116.84 114.935)
	)
	(no_connect
		(at 37.465 51.435)
	)
	(no_connect
		(at 252.73 125.095)
	)
	(no_connect
		(at 116.84 117.475)
	)
	(no_connect
		(at 116.84 71.755)
	)
	(no_connect
		(at 302.895 48.895)
	)
	(no_connect
		(at 37.465 140.335)
	)
	(no_connect
		(at 252.73 69.215)
	)
	(no_connect
		(at 302.895 56.515)
	)
	(no_connect
		(at 173.355 122.555)
	)
	(no_connect
		(at 37.465 76.835)
	)
	(no_connect
		(at 173.355 51.435)
	)
	(wire
		(pts
			(xy 170.815 81.915) (xy 173.355 81.915)
		)
		(stroke
			(width 0)
			(type default)
		)
	)
	(wire
		(pts
			(xy 382.27 41.275) (xy 384.81 41.275)
		)
		(stroke
			(width 0)
			(type default)
		)
	)
	(wire
		(pts
			(xy 384.81 81.915) (xy 382.27 81.915)
		)
		(stroke
			(width 0)
			(type default)
		)
	)
	(wire
		(pts
			(xy 365.76 224.79) (xy 365.76 226.06)
		)
		(stroke
			(width 0)
			(type default)
		)
	)
	(wire
		(pts
			(xy 385.445 160.655) (xy 382.27 160.655)
		)
		(stroke
			(width 0)
			(type default)
		)
	)
	(wire
		(pts
			(xy 384.81 64.135) (xy 382.27 64.135)
		)
		(stroke
			(width 0)
			(type default)
		)
	)
	(wire
		(pts
			(xy 170.815 160.655) (xy 173.355 160.655)
		)
		(stroke
			(width 0)
			(type default)
		)
	)
	(wire
		(pts
			(xy 252.73 102.235) (xy 255.27 102.235)
		)
		(stroke
			(width 0)
			(type default)
		)
	)
	(wire
		(pts
			(xy 382.27 142.875) (xy 384.81 142.875)
		)
		(stroke
			(width 0)
			(type default)
		)
	)
	(wire
		(pts
			(xy 384.81 51.435) (xy 382.27 51.435)
		)
		(stroke
			(width 0)
			(type default)
		)
	)
	(wire
		(pts
			(xy 34.925 147.955) (xy 37.465 147.955)
		)
		(stroke
			(width 0)
			(type default)
		)
	)
	(wire
		(pts
			(xy 355.6 224.79) (xy 365.76 224.79)
		)
		(stroke
			(width 0)
			(type default)
		)
	)
	(wire
		(pts
			(xy 384.81 76.835) (xy 382.27 76.835)
		)
		(stroke
			(width 0)
			(type default)
		)
	)
	(wire
		(pts
			(xy 37.465 59.055) (xy 34.925 59.055)
		)
		(stroke
			(width 0)
			(type default)
		)
	)
	(wire
		(pts
			(xy 116.84 150.495) (xy 119.38 150.495)
		)
		(stroke
			(width 0)
			(type default)
		)
	)
	(wire
		(pts
			(xy 382.27 145.415) (xy 384.81 145.415)
		)
		(stroke
			(width 0)
			(type default)
		)
	)
	(wire
		(pts
			(xy 365.76 224.79) (xy 369.57 224.79)
		)
		(stroke
			(width 0)
			(type default)
		)
	)
	(wire
		(pts
			(xy 343.535 224.79) (xy 343.535 226.06)
		)
		(stroke
			(width 0)
			(type default)
		)
	)
	(wire
		(pts
			(xy 34.925 125.095) (xy 37.465 125.095)
		)
		(stroke
			(width 0)
			(type default)
		)
	)
	(wire
		(pts
			(xy 384.81 89.535) (xy 382.27 89.535)
		)
		(stroke
			(width 0)
			(type default)
		)
	)
	(wire
		(pts
			(xy 365.76 231.14) (xy 365.76 232.41)
		)
		(stroke
			(width 0)
			(type default)
		)
	)
	(wire
		(pts
			(xy 384.81 56.515) (xy 382.27 56.515)
		)
		(stroke
			(width 0)
			(type default)
		)
	)
	(wire
		(pts
			(xy 37.465 92.075) (xy 33.655 92.075)
		)
		(stroke
			(width 0)
			(type default)
		)
	)
	(wire
		(pts
			(xy 116.84 51.435) (xy 119.38 51.435)
		)
		(stroke
			(width 0)
			(type default)
		)
	)
	(wire
		(pts
			(xy 310.515 225.425) (xy 316.23 225.425)
		)
		(stroke
			(width 0)
			(type default)
		)
	)
	(wire
		(pts
			(xy 382.27 109.855) (xy 384.81 109.855)
		)
		(stroke
			(width 0)
			(type default)
		)
	)
	(wire
		(pts
			(xy 34.925 155.575) (xy 37.465 155.575)
		)
		(stroke
			(width 0)
			(type default)
		)
	)
	(wire
		(pts
			(xy 170.815 163.195) (xy 173.355 163.195)
		)
		(stroke
			(width 0)
			(type default)
		)
	)
	(wire
		(pts
			(xy 34.925 137.795) (xy 37.465 137.795)
		)
		(stroke
			(width 0)
			(type default)
		)
	)
	(wire
		(pts
			(xy 382.27 122.555) (xy 384.81 122.555)
		)
		(stroke
			(width 0)
			(type default)
		)
	)
	(wire
		(pts
			(xy 170.815 158.115) (xy 173.355 158.115)
		)
		(stroke
			(width 0)
			(type default)
		)
	)
	(wire
		(pts
			(xy 384.81 66.675) (xy 382.27 66.675)
		)
		(stroke
			(width 0)
			(type default)
		)
	)
	(wire
		(pts
			(xy 33.655 81.915) (xy 37.465 81.915)
		)
		(stroke
			(width 0)
			(type default)
		)
	)
	(wire
		(pts
			(xy 170.815 142.875) (xy 173.355 142.875)
		)
		(stroke
			(width 0)
			(type default)
		)
	)
	(wire
		(pts
			(xy 385.445 155.575) (xy 382.27 155.575)
		)
		(stroke
			(width 0)
			(type default)
		)
	)
	(wire
		(pts
			(xy 33.655 86.995) (xy 37.465 86.995)
		)
		(stroke
			(width 0)
			(type default)
		)
	)
	(wire
		(pts
			(xy 382.27 114.935) (xy 384.81 114.935)
		)
		(stroke
			(width 0)
			(type default)
		)
	)
	(wire
		(pts
			(xy 116.84 69.215) (xy 119.38 69.215)
		)
		(stroke
			(width 0)
			(type default)
		)
	)
	(wire
		(pts
			(xy 385.445 158.115) (xy 382.27 158.115)
		)
		(stroke
			(width 0)
			(type default)
		)
	)
	(wire
		(pts
			(xy 34.925 61.595) (xy 37.465 61.595)
		)
		(stroke
			(width 0)
			(type default)
		)
	)
	(wire
		(pts
			(xy 384.81 69.215) (xy 382.27 69.215)
		)
		(stroke
			(width 0)
			(type default)
		)
	)
	(wire
		(pts
			(xy 384.81 92.075) (xy 382.27 92.075)
		)
		(stroke
			(width 0)
			(type default)
		)
	)
	(wire
		(pts
			(xy 382.27 107.315) (xy 384.81 107.315)
		)
		(stroke
			(width 0)
			(type default)
		)
	)
	(wire
		(pts
			(xy 116.84 53.975) (xy 119.38 53.975)
		)
		(stroke
			(width 0)
			(type default)
		)
	)
	(wire
		(pts
			(xy 34.925 150.495) (xy 37.465 150.495)
		)
		(stroke
			(width 0)
			(type default)
		)
	)
	(wire
		(pts
			(xy 321.31 225.425) (xy 328.93 225.425)
		)
		(stroke
			(width 0)
			(type default)
		)
	)
	(wire
		(pts
			(xy 116.84 43.815) (xy 119.38 43.815)
		)
		(stroke
			(width 0)
			(type default)
		)
	)
	(wire
		(pts
			(xy 252.73 120.015) (xy 255.27 120.015)
		)
		(stroke
			(width 0)
			(type default)
		)
	)
	(wire
		(pts
			(xy 343.535 223.52) (xy 343.535 224.79)
		)
		(stroke
			(width 0)
			(type default)
		)
	)
	(wire
		(pts
			(xy 300.355 140.335) (xy 302.895 140.335)
		)
		(stroke
			(width 0)
			(type default)
		)
	)
	(wire
		(pts
			(xy 170.815 59.055) (xy 173.355 59.055)
		)
		(stroke
			(width 0)
			(type default)
		)
	)
	(wire
		(pts
			(xy 382.27 71.755) (xy 384.81 71.755)
		)
		(stroke
			(width 0)
			(type default)
		)
	)
	(wire
		(pts
			(xy 116.84 89.535) (xy 119.38 89.535)
		)
		(stroke
			(width 0)
			(type default)
		)
	)
	(wire
		(pts
			(xy 37.465 79.375) (xy 33.655 79.375)
		)
		(stroke
			(width 0)
			(type default)
		)
	)
	(wire
		(pts
			(xy 355.6 224.79) (xy 355.6 226.06)
		)
		(stroke
			(width 0)
			(type default)
		)
	)
	(wire
		(pts
			(xy 382.27 147.955) (xy 384.81 147.955)
		)
		(stroke
			(width 0)
			(type default)
		)
	)
	(wire
		(pts
			(xy 382.27 150.495) (xy 384.81 150.495)
		)
		(stroke
			(width 0)
			(type default)
		)
	)
	(wire
		(pts
			(xy 34.925 109.855) (xy 37.465 109.855)
		)
		(stroke
			(width 0)
			(type default)
		)
	)
	(wire
		(pts
			(xy 384.81 53.975) (xy 382.27 53.975)
		)
		(stroke
			(width 0)
			(type default)
		)
	)
	(wire
		(pts
			(xy 33.655 84.455) (xy 37.465 84.455)
		)
		(stroke
			(width 0)
			(type default)
		)
	)
	(polyline
		(pts
			(xy 420.37 10.795) (xy 420.37 191.135)
		)
		(stroke
			(width 0)
			(type default)
		)
	)
	(wire
		(pts
			(xy 382.27 117.475) (xy 384.81 117.475)
		)
		(stroke
			(width 0)
			(type default)
		)
	)
	(wire
		(pts
			(xy 34.29 97.155) (xy 37.465 97.155)
		)
		(stroke
			(width 0)
			(type default)
		)
	)
	(wire
		(pts
			(xy 116.84 153.035) (xy 119.38 153.035)
		)
		(stroke
			(width 0)
			(type default)
		)
	)
	(wire
		(pts
			(xy 170.815 92.075) (xy 173.355 92.075)
		)
		(stroke
			(width 0)
			(type default)
		)
	)
	(wire
		(pts
			(xy 252.73 114.935) (xy 255.27 114.935)
		)
		(stroke
			(width 0)
			(type default)
		)
	)
	(wire
		(pts
			(xy 255.27 97.155) (xy 252.73 97.155)
		)
		(stroke
			(width 0)
			(type default)
		)
	)
	(wire
		(pts
			(xy 116.84 163.195) (xy 119.38 163.195)
		)
		(stroke
			(width 0)
			(type default)
		)
	)
	(wire
		(pts
			(xy 116.84 56.515) (xy 119.38 56.515)
		)
		(stroke
			(width 0)
			(type default)
		)
	)
	(wire
		(pts
			(xy 170.815 130.175) (xy 173.355 130.175)
		)
		(stroke
			(width 0)
			(type default)
		)
	)
	(wire
		(pts
			(xy 384.81 153.035) (xy 382.27 153.035)
		)
		(stroke
			(width 0)
			(type default)
		)
	)
	(wire
		(pts
			(xy 328.93 225.425) (xy 328.93 227.965)
		)
		(stroke
			(width 0)
			(type default)
		)
	)
	(wire
		(pts
			(xy 302.895 137.795) (xy 300.355 137.795)
		)
		(stroke
			(width 0)
			(type default)
		)
	)
	(wire
		(pts
			(xy 384.81 86.995) (xy 382.27 86.995)
		)
		(stroke
			(width 0)
			(type default)
		)
	)
	(wire
		(pts
			(xy 116.84 99.695) (xy 119.38 99.695)
		)
		(stroke
			(width 0)
			(type default)
		)
	)
	(wire
		(pts
			(xy 34.925 120.015) (xy 37.465 120.015)
		)
		(stroke
			(width 0)
			(type default)
		)
	)
	(wire
		(pts
			(xy 52.07 236.22) (xy 52.07 233.68)
		)
		(stroke
			(width 0)
			(type default)
		)
	)
	(wire
		(pts
			(xy 252.73 127.635) (xy 255.27 127.635)
		)
		(stroke
			(width 0)
			(type default)
		)
	)
	(wire
		(pts
			(xy 170.815 147.955) (xy 173.355 147.955)
		)
		(stroke
			(width 0)
			(type default)
		)
	)
	(wire
		(pts
			(xy 382.27 104.775) (xy 384.81 104.775)
		)
		(stroke
			(width 0)
			(type default)
		)
	)
	(wire
		(pts
			(xy 173.355 48.895) (xy 170.815 48.895)
		)
		(stroke
			(width 0)
			(type default)
		)
	)
	(wire
		(pts
			(xy 170.815 155.575) (xy 173.355 155.575)
		)
		(stroke
			(width 0)
			(type default)
		)
	)
	(wire
		(pts
			(xy 37.465 114.935) (xy 34.925 114.935)
		)
		(stroke
			(width 0)
			(type default)
		)
	)
	(wire
		(pts
			(xy 116.84 46.355) (xy 119.38 46.355)
		)
		(stroke
			(width 0)
			(type default)
		)
	)
	(wire
		(pts
			(xy 170.815 84.455) (xy 173.355 84.455)
		)
		(stroke
			(width 0)
			(type default)
		)
	)
	(wire
		(pts
			(xy 300.355 71.755) (xy 302.895 71.755)
		)
		(stroke
			(width 0)
			(type default)
		)
	)
	(wire
		(pts
			(xy 382.27 102.235) (xy 384.81 102.235)
		)
		(stroke
			(width 0)
			(type default)
		)
	)
	(wire
		(pts
			(xy 355.6 231.14) (xy 355.6 232.41)
		)
		(stroke
			(width 0)
			(type default)
		)
	)
	(polyline
		(pts
			(xy 146.05 201.295) (xy 146.05 12.065)
		)
		(stroke
			(width 0)
			(type default)
		)
	)
	(wire
		(pts
			(xy 300.355 125.095) (xy 302.895 125.095)
		)
		(stroke
			(width 0)
			(type default)
		)
	)
	(wire
		(pts
			(xy 252.73 117.475) (xy 255.27 117.475)
		)
		(stroke
			(width 0)
			(type default)
		)
	)
	(wire
		(pts
			(xy 34.925 130.175) (xy 37.465 130.175)
		)
		(stroke
			(width 0)
			(type default)
		)
	)
	(wire
		(pts
			(xy 50.8 238.76) (xy 50.8 241.3)
		)
		(stroke
			(width 0)
			(type default)
		)
	)
	(wire
		(pts
			(xy 93.98 232.41) (xy 93.98 233.68)
		)
		(stroke
			(width 0)
			(type default)
		)
	)
	(wire
		(pts
			(xy 34.925 132.715) (xy 37.465 132.715)
		)
		(stroke
			(width 0)
			(type default)
		)
	)
	(wire
		(pts
			(xy 37.465 117.475) (xy 34.925 117.475)
		)
		(stroke
			(width 0)
			(type default)
		)
	)
	(wire
		(pts
			(xy 52.07 233.68) (xy 54.61 233.68)
		)
		(stroke
			(width 0)
			(type default)
		)
	)
	(wire
		(pts
			(xy 173.355 76.835) (xy 170.815 76.835)
		)
		(stroke
			(width 0)
			(type default)
		)
	)
	(wire
		(pts
			(xy 382.27 137.795) (xy 384.81 137.795)
		)
		(stroke
			(width 0)
			(type default)
		)
	)
	(wire
		(pts
			(xy 382.27 125.095) (xy 384.81 125.095)
		)
		(stroke
			(width 0)
			(type default)
		)
	)
	(wire
		(pts
			(xy 300.355 61.595) (xy 302.895 61.595)
		)
		(stroke
			(width 0)
			(type default)
		)
	)
	(wire
		(pts
			(xy 252.73 86.995) (xy 255.27 86.995)
		)
		(stroke
			(width 0)
			(type default)
		)
	)
	(wire
		(pts
			(xy 170.815 86.995) (xy 173.355 86.995)
		)
		(stroke
			(width 0)
			(type default)
		)
	)
	(wire
		(pts
			(xy 384.81 84.455) (xy 382.27 84.455)
		)
		(stroke
			(width 0)
			(type default)
		)
	)
	(wire
		(pts
			(xy 343.535 231.14) (xy 343.535 232.41)
		)
		(stroke
			(width 0)
			(type default)
		)
	)
	(wire
		(pts
			(xy 384.81 79.375) (xy 382.27 79.375)
		)
		(stroke
			(width 0)
			(type default)
		)
	)
	(wire
		(pts
			(xy 385.445 165.735) (xy 382.27 165.735)
		)
		(stroke
			(width 0)
			(type default)
		)
	)
	(wire
		(pts
			(xy 343.535 224.79) (xy 355.6 224.79)
		)
		(stroke
			(width 0)
			(type default)
		)
	)
	(wire
		(pts
			(xy 93.98 238.76) (xy 93.98 240.03)
		)
		(stroke
			(width 0)
			(type default)
		)
	)
	(wire
		(pts
			(xy 116.84 122.555) (xy 119.38 122.555)
		)
		(stroke
			(width 0)
			(type default)
		)
	)
	(wire
		(pts
			(xy 170.815 145.415) (xy 173.355 145.415)
		)
		(stroke
			(width 0)
			(type default)
		)
	)
	(wire
		(pts
			(xy 170.815 89.535) (xy 173.355 89.535)
		)
		(stroke
			(width 0)
			(type default)
		)
	)
	(polyline
		(pts
			(xy 277.495 12.065) (xy 277.495 201.295)
		)
		(stroke
			(width 0)
			(type default)
		)
	)
	(wire
		(pts
			(xy 300.355 135.255) (xy 302.895 135.255)
		)
		(stroke
			(width 0)
			(type default)
		)
	)
	(wire
		(pts
			(xy 34.925 122.555) (xy 37.465 122.555)
		)
		(stroke
			(width 0)
			(type default)
		)
	)
	(wire
		(pts
			(xy 119.38 48.895) (xy 116.84 48.895)
		)
		(stroke
			(width 0)
			(type default)
		)
	)
	(wire
		(pts
			(xy 382.27 112.395) (xy 384.81 112.395)
		)
		(stroke
			(width 0)
			(type default)
		)
	)
	(wire
		(pts
			(xy 54.61 236.22) (xy 52.07 236.22)
		)
		(stroke
			(width 0)
			(type default)
		)
	)
	(wire
		(pts
			(xy 300.355 69.215) (xy 302.895 69.215)
		)
		(stroke
			(width 0)
			(type default)
		)
	)
	(wire
		(pts
			(xy 116.84 92.075) (xy 119.38 92.075)
		)
		(stroke
			(width 0)
			(type default)
		)
	)
	(wire
		(pts
			(xy 170.815 79.375) (xy 173.355 79.375)
		)
		(stroke
			(width 0)
			(type default)
		)
	)
	(wire
		(pts
			(xy 384.81 43.815) (xy 382.27 43.815)
		)
		(stroke
			(width 0)
			(type default)
		)
	)
	(wire
		(pts
			(xy 173.355 74.295) (xy 170.815 74.295)
		)
		(stroke
			(width 0)
			(type default)
		)
	)
	(wire
		(pts
			(xy 385.445 163.195) (xy 382.27 163.195)
		)
		(stroke
			(width 0)
			(type default)
		)
	)
	(wire
		(pts
			(xy 382.27 97.155) (xy 384.81 97.155)
		)
		(stroke
			(width 0)
			(type default)
		)
	)
	(wire
		(pts
			(xy 173.355 99.695) (xy 170.815 99.695)
		)
		(stroke
			(width 0)
			(type default)
		)
	)
	(wire
		(pts
			(xy 116.84 120.015) (xy 119.38 120.015)
		)
		(stroke
			(width 0)
			(type default)
		)
	)
	(wire
		(pts
			(xy 384.81 61.595) (xy 382.27 61.595)
		)
		(stroke
			(width 0)
			(type default)
		)
	)
	(wire
		(pts
			(xy 300.355 158.115) (xy 302.895 158.115)
		)
		(stroke
			(width 0)
			(type default)
		)
	)
	(wire
		(pts
			(xy 170.815 61.595) (xy 173.355 61.595)
		)
		(stroke
			(width 0)
			(type default)
		)
	)
	(wire
		(pts
			(xy 37.465 127.635) (xy 34.925 127.635)
		)
		(stroke
			(width 0)
			(type default)
		)
	)
	(wire
		(pts
			(xy 343.535 214.63) (xy 343.535 218.44)
		)
		(stroke
			(width 0)
			(type default)
		)
	)
	(wire
		(pts
			(xy 316.23 216.535) (xy 310.515 216.535)
		)
		(stroke
			(width 0)
			(type default)
		)
	)
	(wire
		(pts
			(xy 384.81 59.055) (xy 382.27 59.055)
		)
		(stroke
			(width 0)
			(type default)
		)
	)
	(wire
		(pts
			(xy 116.84 160.655) (xy 119.38 160.655)
		)
		(stroke
			(width 0)
			(type default)
		)
	)
	(wire
		(pts
			(xy 382.27 127.635) (xy 384.81 127.635)
		)
		(stroke
			(width 0)
			(type default)
		)
	)
	(wire
		(pts
			(xy 384.81 74.295) (xy 382.27 74.295)
		)
		(stroke
			(width 0)
			(type default)
		)
	)
	(wire
		(pts
			(xy 384.81 48.895) (xy 382.27 48.895)
		)
		(stroke
			(width 0)
			(type default)
		)
	)
	(wire
		(pts
			(xy 170.815 109.855) (xy 173.355 109.855)
		)
		(stroke
			(width 0)
			(type default)
		)
	)
	(wire
		(pts
			(xy 384.81 46.355) (xy 382.27 46.355)
		)
		(stroke
			(width 0)
			(type default)
		)
	)
	(wire
		(pts
			(xy 384.81 94.615) (xy 382.27 94.615)
		)
		(stroke
			(width 0)
			(type default)
		)
	)
	(wire
		(pts
			(xy 252.73 104.775) (xy 255.27 104.775)
		)
		(stroke
			(width 0)
			(type default)
		)
	)
	(wire
		(pts
			(xy 382.27 140.335) (xy 384.81 140.335)
		)
		(stroke
			(width 0)
			(type default)
		)
	)
	(wire
		(pts
			(xy 34.925 112.395) (xy 37.465 112.395)
		)
		(stroke
			(width 0)
			(type default)
		)
	)
	(wire
		(pts
			(xy 302.895 142.875) (xy 300.355 142.875)
		)
		(stroke
			(width 0)
			(type default)
		)
	)
	(wire
		(pts
			(xy 321.31 216.535) (xy 326.39 216.535)
		)
		(stroke
			(width 0)
			(type default)
		)
	)
	(wire
		(pts
			(xy 173.355 132.715) (xy 170.815 132.715)
		)
		(stroke
			(width 0)
			(type default)
		)
	)
	(wire
		(pts
			(xy 34.925 158.115) (xy 37.465 158.115)
		)
		(stroke
			(width 0)
			(type default)
		)
	)
	(wire
		(pts
			(xy 170.815 104.775) (xy 173.355 104.775)
		)
		(stroke
			(width 0)
			(type default)
		)
	)
	(wire
		(pts
			(xy 50.8 233.68) (xy 52.07 233.68)
		)
		(stroke
			(width 0)
			(type default)
		)
	)
	(wire
		(pts
			(xy 34.925 153.035) (xy 37.465 153.035)
		)
		(stroke
			(width 0)
			(type default)
		)
	)
	(wire
		(pts
			(xy 73.66 233.68) (xy 76.2 233.68)
		)
		(stroke
			(width 0)
			(type default)
		)
	)
	(wire
		(pts
			(xy 34.925 74.295) (xy 37.465 74.295)
		)
		(stroke
			(width 0)
			(type default)
		)
	)
	(wire
		(pts
			(xy 170.815 137.795) (xy 173.355 137.795)
		)
		(stroke
			(width 0)
			(type default)
		)
	)
	(wire
		(pts
			(xy 54.61 238.76) (xy 50.8 238.76)
		)
		(stroke
			(width 0)
			(type default)
		)
	)
	(wire
		(pts
			(xy 252.73 84.455) (xy 255.27 84.455)
		)
		(stroke
			(width 0)
			(type default)
		)
	)
	(wire
		(pts
			(xy 382.27 130.175) (xy 384.81 130.175)
		)
		(stroke
			(width 0)
			(type default)
		)
	)
	(global_label "DQ01_A"
		(shape input)
		(at 384.81 61.595 0)
		(fields_autoplaced yes)
		(effects
			(font
				(size 1.27 1.27)
			)
			(justify left)
		)
		(property "Intersheetrefs" "${INTERSHEET_REFS}"
			(at 394.2099 61.5156 0)
			(effects
				(font
					(size 1.27 1.27)
				)
				(justify left)
				(hide yes)
			)
		)
	)
	(global_label "ETH_MDC"
		(shape input)
		(at 170.815 89.535 180)
		(fields_autoplaced yes)
		(effects
			(font
				(size 1.27 1.27)
			)
			(justify right)
		)
		(property "Intersheetrefs" "${INTERSHEET_REFS}"
			(at 160.0846 89.4556 0)
			(effects
				(font
					(size 1.27 1.27)
				)
				(justify right)
				(hide yes)
			)
		)
	)
	(global_label "USR_LED5"
		(shape input)
		(at 255.27 84.455 0)
		(fields_autoplaced yes)
		(effects
			(font
				(size 1.27 1.27)
			)
			(justify left)
		)
		(property "Intersheetrefs" "${INTERSHEET_REFS}"
			(at 267.0285 84.3756 0)
			(effects
				(font
					(size 1.27 1.27)
				)
				(justify left)
				(hide yes)
			)
		)
	)
	(global_label "IO_V12"
		(shape input)
		(at 300.355 158.115 180)
		(fields_autoplaced yes)
		(effects
			(font
				(size 1.27 1.27)
			)
			(justify right)
		)
		(property "Intersheetrefs" "${INTERSHEET_REFS}"
			(at 291.6203 158.0356 0)
			(effects
				(font
					(size 1.27 1.27)
				)
				(justify right)
				(hide yes)
			)
		)
	)
	(global_label "IO_M5"
		(shape input)
		(at 384.81 84.455 0)
		(fields_autoplaced yes)
		(effects
			(font
				(size 1.27 1.27)
			)
			(justify left)
		)
		(property "Intersheetrefs" "${INTERSHEET_REFS}"
			(at 392.698 84.3756 0)
			(effects
				(font
					(size 1.27 1.27)
				)
				(justify left)
				(hide yes)
			)
		)
	)
	(global_label "IO_AA11"
		(shape input)
		(at 300.355 140.335 180)
		(fields_autoplaced yes)
		(effects
			(font
				(size 1.27 1.27)
			)
			(justify right)
		)
		(property "Intersheetrefs" "${INTERSHEET_REFS}"
			(at 290.5318 140.2556 0)
			(effects
				(font
					(size 1.27 1.27)
				)
				(justify right)
				(hide yes)
			)
		)
	)
	(global_label "ETH_RXD3"
		(shape input)
		(at 170.815 61.595 180)
		(fields_autoplaced yes)
		(effects
			(font
				(size 1.27 1.27)
			)
			(justify right)
		)
		(property "Intersheetrefs" "${INTERSHEET_REFS}"
			(at 159.117 61.5156 0)
			(effects
				(font
					(size 1.27 1.27)
				)
				(justify right)
				(hide yes)
			)
		)
	)
	(global_label "IO_Y12"
		(shape input)
		(at 300.355 137.795 180)
		(fields_autoplaced yes)
		(effects
			(font
				(size 1.27 1.27)
			)
			(justify right)
		)
		(property "Intersheetrefs" "${INTERSHEET_REFS}"
			(at 291.6203 137.7156 0)
			(effects
				(font
					(size 1.27 1.27)
				)
				(justify right)
				(hide yes)
			)
		)
	)
	(global_label "VREF_34"
		(shape input)
		(at 384.81 137.795 0)
		(fields_autoplaced yes)
		(effects
			(font
				(size 1.27 1.27)
			)
			(justify left)
		)
		(property "Intersheetrefs" "${INTERSHEET_REFS}"
			(at 395.1171 137.7156 0)
			(effects
				(font
					(size 1.27 1.27)
				)
				(justify left)
				(hide yes)
			)
		)
	)
	(global_label "CA4_A"
		(shape input)
		(at 385.445 163.195 0)
		(fields_autoplaced yes)
		(effects
			(font
				(size 1.27 1.27)
			)
			(justify left)
		)
		(property "Intersheetrefs" "${INTERSHEET_REFS}"
			(at 393.3935 163.1156 0)
			(effects
				(font
					(size 1.27 1.27)
				)
				(justify left)
				(hide yes)
			)
		)
	)
	(global_label "DQ07_A"
		(shape input)
		(at 384.81 66.675 0)
		(fields_autoplaced yes)
		(effects
			(font
				(size 1.27 1.27)
			)
			(justify left)
		)
		(property "Intersheetrefs" "${INTERSHEET_REFS}"
			(at 394.2099 66.5956 0)
			(effects
				(font
					(size 1.27 1.27)
				)
				(justify left)
				(hide yes)
			)
		)
	)
	(global_label "VDDQ"
		(shape input)
		(at 343.535 214.63 90)
		(fields_autoplaced yes)
		(effects
			(font
				(size 1.27 1.27)
			)
			(justify left)
		)
		(property "Intersheetrefs" "${INTERSHEET_REFS}"
			(at 343.4556 207.3468 90)
			(effects
				(font
					(size 1.27 1.27)
				)
				(justify left)
				(hide yes)
			)
		)
	)
	(global_label "IO_U12"
		(shape input)
		(at 300.355 125.095 180)
		(fields_autoplaced yes)
		(effects
			(font
				(size 1.27 1.27)
			)
			(justify right)
		)
		(property "Intersheetrefs" "${INTERSHEET_REFS}"
			(at 291.3784 125.0156 0)
			(effects
				(font
					(size 1.27 1.27)
				)
				(justify right)
				(hide yes)
			)
		)
	)
	(global_label "IO_U3"
		(shape input)
		(at 384.81 107.315 0)
		(fields_autoplaced yes)
		(effects
			(font
				(size 1.27 1.27)
			)
			(justify left)
		)
		(property "Intersheetrefs" "${INTERSHEET_REFS}"
			(at 392.5771 107.2356 0)
			(effects
				(font
					(size 1.27 1.27)
				)
				(justify left)
				(hide yes)
			)
		)
	)
	(global_label "IO_W12"
		(shape input)
		(at 300.355 135.255 180)
		(fields_autoplaced yes)
		(effects
			(font
				(size 1.27 1.27)
			)
			(justify right)
		)
		(property "Intersheetrefs" "${INTERSHEET_REFS}"
			(at 291.2575 135.1756 0)
			(effects
				(font
					(size 1.27 1.27)
				)
				(justify right)
				(hide yes)
			)
		)
	)
	(global_label "DQ12_A"
		(shape input)
		(at 384.81 76.835 0)
		(fields_autoplaced yes)
		(effects
			(font
				(size 1.27 1.27)
			)
			(justify left)
		)
		(property "Intersheetrefs" "${INTERSHEET_REFS}"
			(at 394.2099 76.7556 0)
			(effects
				(font
					(size 1.27 1.27)
				)
				(justify left)
				(hide yes)
			)
		)
	)
	(global_label "ETH_MDIO"
		(shape input)
		(at 170.815 74.295 180)
		(fields_autoplaced yes)
		(effects
			(font
				(size 1.27 1.27)
			)
			(justify right)
		)
		(property "Intersheetrefs" "${INTERSHEET_REFS}"
			(at 159.4194 74.2156 0)
			(effects
				(font
					(size 1.27 1.27)
				)
				(justify right)
				(hide yes)
			)
		)
	)
	(global_label "DQ13_A"
		(shape input)
		(at 384.81 89.535 0)
		(fields_autoplaced yes)
		(effects
			(font
				(size 1.27 1.27)
			)
			(justify left)
		)
		(property "Intersheetrefs" "${INTERSHEET_REFS}"
			(at 394.2099 89.4556 0)
			(effects
				(font
					(size 1.27 1.27)
				)
				(justify left)
				(hide yes)
			)
		)
	)
	(global_label "FPGA_AB21_BALL"
		(shape input)
		(at 33.655 81.915 180)
		(fields_autoplaced yes)
		(effects
			(font
				(size 1.27 1.27)
			)
			(justify right)
		)
		(property "Intersheetrefs" "${INTERSHEET_REFS}"
			(at 15.486 81.8356 0)
			(effects
				(font
					(size 1.27 1.27)
				)
				(justify right)
				(hide yes)
			)
		)
	)
	(global_label "SD_DAT2"
		(shape input)
		(at 170.815 130.175 180)
		(fields_autoplaced yes)
		(effects
			(font
				(size 1.27 1.27)
			)
			(justify right)
		)
		(property "Intersheetrefs" "${INTERSHEET_REFS}"
			(at 160.5079 130.0956 0)
			(effects
				(font
					(size 1.27 1.27)
				)
				(justify right)
				(hide yes)
			)
		)
	)
	(global_label "TMDS_D0_N"
		(shape input)
		(at 119.38 153.035 0)
		(fields_autoplaced yes)
		(effects
			(font
				(size 1.27 1.27)
			)
			(justify left)
		)
		(property "Intersheetrefs" "${INTERSHEET_REFS}"
			(at 132.348 152.9556 0)
			(effects
				(font
					(size 1.27 1.27)
				)
				(justify left)
				(hide yes)
			)
		)
	)
	(global_label "AUX_JTAG_TDO"
		(shape input)
		(at 34.925 59.055 180)
		(fields_autoplaced yes)
		(effects
			(font
				(size 1.27 1.27)
			)
			(justify right)
		)
		(property "Intersheetrefs" "${INTERSHEET_REFS}"
			(at 19.1751 58.9756 0)
			(effects
				(font
					(size 1.27 1.27)
				)
				(justify right)
				(hide yes)
			)
		)
	)
	(global_label "USR_LED1"
		(shape input)
		(at 255.27 97.155 0)
		(fields_autoplaced yes)
		(effects
			(font
				(size 1.27 1.27)
			)
			(justify left)
		)
		(property "Intersheetrefs" "${INTERSHEET_REFS}"
			(at 267.0285 97.0756 0)
			(effects
				(font
					(size 1.27 1.27)
				)
				(justify left)
				(hide yes)
			)
		)
	)
	(global_label "SD_DAT3"
		(shape input)
		(at 170.815 132.715 180)
		(fields_autoplaced yes)
		(effects
			(font
				(size 1.27 1.27)
			)
			(justify right)
		)
		(property "Intersheetrefs" "${INTERSHEET_REFS}"
			(at 160.5079 132.6356 0)
			(effects
				(font
					(size 1.27 1.27)
				)
				(justify right)
				(hide yes)
			)
		)
	)
	(global_label "HR_DQ5"
		(shape input)
		(at 34.925 155.575 180)
		(fields_autoplaced yes)
		(effects
			(font
				(size 1.27 1.27)
			)
			(justify right)
		)
		(property "Intersheetrefs" "${INTERSHEET_REFS}"
			(at 25.2227 155.4956 0)
			(effects
				(font
					(size 1.27 1.27)
				)
				(justify right)
				(hide yes)
			)
		)
	)
	(global_label "USR_BTN2"
		(shape input)
		(at 255.27 120.015 0)
		(fields_autoplaced yes)
		(effects
			(font
				(size 1.27 1.27)
			)
			(justify left)
		)
		(property "Intersheetrefs" "${INTERSHEET_REFS}"
			(at 267.1494 119.9356 0)
			(effects
				(font
					(size 1.27 1.27)
				)
				(justify left)
				(hide yes)
			)
		)
	)
	(global_label "HR_CKN"
		(shape input)
		(at 34.925 122.555 180)
		(fields_autoplaced yes)
		(effects
			(font
				(size 1.27 1.27)
			)
			(justify right)
		)
		(property "Intersheetrefs" "${INTERSHEET_REFS}"
			(at 25.1622 122.4756 0)
			(effects
				(font
					(size 1.27 1.27)
				)
				(justify right)
				(hide yes)
			)
		)
	)
	(global_label "TMDS_CLK_P"
		(shape input)
		(at 119.38 160.655 0)
		(fields_autoplaced yes)
		(effects
			(font
				(size 1.27 1.27)
			)
			(justify left)
		)
		(property "Intersheetrefs" "${INTERSHEET_REFS}"
			(at 133.3761 160.5756 0)
			(effects
				(font
					(size 1.27 1.27)
				)
				(justify left)
				(hide yes)
			)
		)
	)
	(global_label "UART1_RX"
		(shape input)
		(at 33.655 92.075 180)
		(fields_autoplaced yes)
		(effects
			(font
				(size 1.27 1.27)
			)
			(justify right)
		)
		(property "Intersheetrefs" "${INTERSHEET_REFS}"
			(at 22.0175 91.9956 0)
			(effects
				(font
					(size 1.27 1.27)
				)
				(justify right)
				(hide yes)
			)
		)
	)
	(global_label "AUX_JTAG_TDI"
		(shape input)
		(at 34.29 97.155 180)
		(fields_autoplaced yes)
		(effects
			(font
				(size 1.27 1.27)
			)
			(justify right)
		)
		(property "Intersheetrefs" "${INTERSHEET_REFS}"
			(at 19.2658 97.0756 0)
			(effects
				(font
					(size 1.27 1.27)
				)
				(justify right)
				(hide yes)
			)
		)
	)
	(global_label "3V3_SYS"
		(shape input)
		(at 50.8 233.68 180)
		(fields_autoplaced yes)
		(effects
			(font
				(size 1.27 1.27)
			)
			(justify right)
		)
		(property "Intersheetrefs" "${INTERSHEET_REFS}"
			(at 40.4929 233.7594 0)
			(effects
				(font
					(size 1.27 1.27)
				)
				(justify right)
				(hide yes)
			)
		)
	)
	(global_label "TMDS_D1_N"
		(shape input)
		(at 119.38 122.555 0)
		(fields_autoplaced yes)
		(effects
			(font
				(size 1.27 1.27)
			)
			(justify left)
		)
		(property "Intersheetrefs" "${INTERSHEET_REFS}"
			(at 132.348 122.4756 0)
			(effects
				(font
					(size 1.27 1.27)
				)
				(justify left)
				(hide yes)
			)
		)
	)
	(global_label "AUX_JTAG_TMS"
		(shape input)
		(at 34.925 74.295 180)
		(fields_autoplaced yes)
		(effects
			(font
				(size 1.27 1.27)
			)
			(justify right)
		)
		(property "Intersheetrefs" "${INTERSHEET_REFS}"
			(at 19.1146 74.2156 0)
			(effects
				(font
					(size 1.27 1.27)
				)
				(justify right)
				(hide yes)
			)
		)
	)
	(global_label "HR_DQ7"
		(shape input)
		(at 34.925 109.855 180)
		(fields_autoplaced yes)
		(effects
			(font
				(size 1.27 1.27)
			)
			(justify right)
		)
		(property "Intersheetrefs" "${INTERSHEET_REFS}"
			(at 25.2227 109.7756 0)
			(effects
				(font
					(size 1.27 1.27)
				)
				(justify right)
				(hide yes)
			)
		)
	)
	(global_label "VRP"
		(shape input)
		(at 310.515 225.425 180)
		(fields_autoplaced yes)
		(effects
			(font
				(size 1.27 1.27)
			)
			(justify right)
		)
		(property "Intersheetrefs" "${INTERSHEET_REFS}"
			(at 304.5622 225.3456 0)
			(effects
				(font
					(size 1.27 1.27)
				)
				(justify right)
				(hide yes)
			)
		)
	)
	(global_label "USR_BTN3"
		(shape input)
		(at 255.27 104.775 0)
		(fields_autoplaced yes)
		(effects
			(font
				(size 1.27 1.27)
			)
			(justify left)
		)
		(property "Intersheetrefs" "${INTERSHEET_REFS}"
			(at 267.1494 104.6956 0)
			(effects
				(font
					(size 1.27 1.27)
				)
				(justify left)
				(hide yes)
			)
		)
	)
	(global_label "CA_0A"
		(shape input)
		(at 384.81 43.815 0)
		(fields_autoplaced yes)
		(effects
			(font
				(size 1.27 1.27)
			)
			(justify left)
		)
		(property "Intersheetrefs" "${INTERSHEET_REFS}"
			(at 392.7585 43.7356 0)
			(effects
				(font
					(size 1.27 1.27)
				)
				(justify left)
				(hide yes)
			)
		)
	)
	(global_label "HR_RST"
		(shape input)
		(at 34.925 137.795 180)
		(fields_autoplaced yes)
		(effects
			(font
				(size 1.27 1.27)
			)
			(justify right)
		)
		(property "Intersheetrefs" "${INTERSHEET_REFS}"
			(at 25.5856 137.7156 0)
			(effects
				(font
					(size 1.27 1.27)
				)
				(justify right)
				(hide yes)
			)
		)
	)
	(global_label "VREF_34"
		(shape input)
		(at 384.81 71.755 0)
		(fields_autoplaced yes)
		(effects
			(font
				(size 1.27 1.27)
			)
			(justify left)
		)
		(property "Intersheetrefs" "${INTERSHEET_REFS}"
			(at 395.1171 71.6756 0)
			(effects
				(font
					(size 1.27 1.27)
				)
				(justify left)
				(hide yes)
			)
		)
	)
	(global_label "TMDS_D2_P"
		(shape input)
		(at 119.38 89.535 0)
		(fields_autoplaced yes)
		(effects
			(font
				(size 1.27 1.27)
			)
			(justify left)
		)
		(property "Intersheetrefs" "${INTERSHEET_REFS}"
			(at 132.2875 89.4556 0)
			(effects
				(font
					(size 1.27 1.27)
				)
				(justify left)
				(hide yes)
			)
		)
	)
	(global_label "TMDS_D0_P"
		(shape input)
		(at 119.38 150.495 0)
		(fields_autoplaced yes)
		(effects
			(font
				(size 1.27 1.27)
			)
			(justify left)
		)
		(property "Intersheetrefs" "${INTERSHEET_REFS}"
			(at 132.2875 150.4156 0)
			(effects
				(font
					(size 1.27 1.27)
				)
				(justify left)
				(hide yes)
			)
		)
	)
	(global_label "ETH_TXD1"
		(shape input)
		(at 170.815 160.655 180)
		(fields_autoplaced yes)
		(effects
			(font
				(size 1.27 1.27)
			)
			(justify right)
		)
		(property "Intersheetrefs" "${INTERSHEET_REFS}"
			(at 159.4194 160.5756 0)
			(effects
				(font
					(size 1.27 1.27)
				)
				(justify right)
				(hide yes)
			)
		)
	)
	(global_label "USR_LED4"
		(shape input)
		(at 255.27 102.235 0)
		(fields_autoplaced yes)
		(effects
			(font
				(size 1.27 1.27)
			)
			(justify left)
		)
		(property "Intersheetrefs" "${INTERSHEET_REFS}"
			(at 267.0285 102.1556 0)
			(effects
				(font
					(size 1.27 1.27)
				)
				(justify left)
				(hide yes)
			)
		)
	)
	(global_label "TMDS_D2_N"
		(shape input)
		(at 119.38 92.075 0)
		(fields_autoplaced yes)
		(effects
			(font
				(size 1.27 1.27)
			)
			(justify left)
		)
		(property "Intersheetrefs" "${INTERSHEET_REFS}"
			(at 132.348 91.9956 0)
			(effects
				(font
					(size 1.27 1.27)
				)
				(justify left)
				(hide yes)
			)
		)
	)
	(global_label "DMI_0A"
		(shape input)
		(at 384.81 46.355 0)
		(fields_autoplaced yes)
		(effects
			(font
				(size 1.27 1.27)
			)
			(justify left)
		)
		(property "Intersheetrefs" "${INTERSHEET_REFS}"
			(at 393.7261 46.2756 0)
			(effects
				(font
					(size 1.27 1.27)
				)
				(justify left)
				(hide yes)
			)
		)
	)
	(global_label "HR_DQ6"
		(shape input)
		(at 34.925 147.955 180)
		(fields_autoplaced yes)
		(effects
			(font
				(size 1.27 1.27)
			)
			(justify right)
		)
		(property "Intersheetrefs" "${INTERSHEET_REFS}"
			(at 25.2227 147.8756 0)
			(effects
				(font
					(size 1.27 1.27)
				)
				(justify right)
				(hide yes)
			)
		)
	)
	(global_label "TMDS_CLK_N"
		(shape input)
		(at 119.38 163.195 0)
		(fields_autoplaced yes)
		(effects
			(font
				(size 1.27 1.27)
			)
			(justify left)
		)
		(property "Intersheetrefs" "${INTERSHEET_REFS}"
			(at 133.4366 163.1156 0)
			(effects
				(font
					(size 1.27 1.27)
				)
				(justify left)
				(hide yes)
			)
		)
	)
	(global_label "HR_CS"
		(shape input)
		(at 34.925 125.095 180)
		(fields_autoplaced yes)
		(effects
			(font
				(size 1.27 1.27)
			)
			(justify right)
		)
		(property "Intersheetrefs" "${INTERSHEET_REFS}"
			(at 26.5532 125.0156 0)
			(effects
				(font
					(size 1.27 1.27)
				)
				(justify right)
				(hide yes)
			)
		)
	)
	(global_label "VRP"
		(shape input)
		(at 385.445 165.735 0)
		(fields_autoplaced yes)
		(effects
			(font
				(size 1.27 1.27)
			)
			(justify left)
		)
		(property "Intersheetrefs" "${INTERSHEET_REFS}"
			(at 391.3978 165.6556 0)
			(effects
				(font
					(size 1.27 1.27)
				)
				(justify left)
				(hide yes)
			)
		)
	)
	(global_label "HR_CKP"
		(shape input)
		(at 34.925 120.015 180)
		(fields_autoplaced yes)
		(effects
			(font
				(size 1.27 1.27)
			)
			(justify right)
		)
		(property "Intersheetrefs" "${INTERSHEET_REFS}"
			(at 25.2227 119.9356 0)
			(effects
				(font
					(size 1.27 1.27)
				)
				(justify right)
				(hide yes)
			)
		)
	)
	(global_label "DQ08_A"
		(shape input)
		(at 384.81 127.635 0)
		(fields_autoplaced yes)
		(effects
			(font
				(size 1.27 1.27)
			)
			(justify left)
		)
		(property "Intersheetrefs" "${INTERSHEET_REFS}"
			(at 394.2099 127.5556 0)
			(effects
				(font
					(size 1.27 1.27)
				)
				(justify left)
				(hide yes)
			)
		)
	)
	(global_label "3V3_SYS"
		(shape input)
		(at 93.98 232.41 90)
		(fields_autoplaced yes)
		(effects
			(font
				(size 1.27 1.27)
			)
			(justify left)
		)
		(property "Intersheetrefs" "${INTERSHEET_REFS}"
			(at 93.9006 222.1029 90)
			(effects
				(font
					(size 1.27 1.27)
				)
				(justify left)
				(hide yes)
			)
		)
	)
	(global_label "SD_CMD"
		(shape input)
		(at 170.815 137.795 180)
		(fields_autoplaced yes)
		(effects
			(font
				(size 1.27 1.27)
			)
			(justify right)
		)
		(property "Intersheetrefs" "${INTERSHEET_REFS}"
			(at 161.0522 137.7156 0)
			(effects
				(font
					(size 1.27 1.27)
				)
				(justify right)
				(hide yes)
			)
		)
	)
	(global_label "ETH_TX_CLK"
		(shape input)
		(at 170.815 104.775 180)
		(fields_autoplaced yes)
		(effects
			(font
				(size 1.27 1.27)
			)
			(justify right)
		)
		(property "Intersheetrefs" "${INTERSHEET_REFS}"
			(at 157.3632 104.6956 0)
			(effects
				(font
					(size 1.27 1.27)
				)
				(justify right)
				(hide yes)
			)
		)
	)
	(global_label "DQ11_A"
		(shape input)
		(at 384.81 153.035 0)
		(fields_autoplaced yes)
		(effects
			(font
				(size 1.27 1.27)
			)
			(justify left)
		)
		(property "Intersheetrefs" "${INTERSHEET_REFS}"
			(at 394.2099 152.9556 0)
			(effects
				(font
					(size 1.27 1.27)
				)
				(justify left)
				(hide yes)
			)
		)
	)
	(global_label "ETH_RSTN"
		(shape input)
		(at 170.815 109.855 180)
		(fields_autoplaced yes)
		(effects
			(font
				(size 1.27 1.27)
			)
			(justify right)
		)
		(property "Intersheetrefs" "${INTERSHEET_REFS}"
			(at 159.2984 109.7756 0)
			(effects
				(font
					(size 1.27 1.27)
				)
				(justify right)
				(hide yes)
			)
		)
	)
	(global_label "DMI_1A"
		(shape input)
		(at 384.81 140.335 0)
		(fields_autoplaced yes)
		(effects
			(font
				(size 1.27 1.27)
			)
			(justify left)
		)
		(property "Intersheetrefs" "${INTERSHEET_REFS}"
			(at 393.7261 140.2556 0)
			(effects
				(font
					(size 1.27 1.27)
				)
				(justify left)
				(hide yes)
			)
		)
	)
	(global_label "IO_AB10"
		(shape input)
		(at 300.355 61.595 180)
		(fields_autoplaced yes)
		(effects
			(font
				(size 1.27 1.27)
			)
			(justify right)
		)
		(property "Intersheetrefs" "${INTERSHEET_REFS}"
			(at 290.3503 61.5156 0)
			(effects
				(font
					(size 1.27 1.27)
				)
				(justify right)
				(hide yes)
			)
		)
	)
	(global_label "HR_DQ4"
		(shape input)
		(at 34.925 153.035 180)
		(fields_autoplaced yes)
		(effects
			(font
				(size 1.27 1.27)
			)
			(justify right)
		)
		(property "Intersheetrefs" "${INTERSHEET_REFS}"
			(at 25.2227 152.9556 0)
			(effects
				(font
					(size 1.27 1.27)
				)
				(justify right)
				(hide yes)
			)
		)
	)
	(global_label "DQ15_A"
		(shape input)
		(at 384.81 92.075 0)
		(fields_autoplaced yes)
		(effects
			(font
				(size 1.27 1.27)
			)
			(justify left)
		)
		(property "Intersheetrefs" "${INTERSHEET_REFS}"
			(at 394.2099 91.9956 0)
			(effects
				(font
					(size 1.27 1.27)
				)
				(justify left)
				(hide yes)
			)
		)
	)
	(global_label "CA2_A"
		(shape input)
		(at 385.445 160.655 0)
		(fields_autoplaced yes)
		(effects
			(font
				(size 1.27 1.27)
			)
			(justify left)
		)
		(property "Intersheetrefs" "${INTERSHEET_REFS}"
			(at 393.3935 160.5756 0)
			(effects
				(font
					(size 1.27 1.27)
				)
				(justify left)
				(hide yes)
			)
		)
	)
	(global_label "USR_LED2"
		(shape input)
		(at 255.27 117.475 0)
		(fields_autoplaced yes)
		(effects
			(font
				(size 1.27 1.27)
			)
			(justify left)
		)
		(property "Intersheetrefs" "${INTERSHEET_REFS}"
			(at 267.0285 117.3956 0)
			(effects
				(font
					(size 1.27 1.27)
				)
				(justify left)
				(hide yes)
			)
		)
	)
	(global_label "DQ04_A"
		(shape input)
		(at 384.81 81.915 0)
		(fields_autoplaced yes)
		(effects
			(font
				(size 1.27 1.27)
			)
			(justify left)
		)
		(property "Intersheetrefs" "${INTERSHEET_REFS}"
			(at 394.2099 81.8356 0)
			(effects
				(font
					(size 1.27 1.27)
				)
				(justify left)
				(hide yes)
			)
		)
	)
	(global_label "CA_1A"
		(shape input)
		(at 384.81 69.215 0)
		(fields_autoplaced yes)
		(effects
			(font
				(size 1.27 1.27)
			)
			(justify left)
		)
		(property "Intersheetrefs" "${INTERSHEET_REFS}"
			(at 392.7585 69.1356 0)
			(effects
				(font
					(size 1.27 1.27)
				)
				(justify left)
				(hide yes)
			)
		)
	)
	(global_label "CK_A_N"
		(shape input)
		(at 384.81 147.955 0)
		(fields_autoplaced yes)
		(effects
			(font
				(size 1.27 1.27)
			)
			(justify left)
		)
		(property "Intersheetrefs" "${INTERSHEET_REFS}"
			(at 394.0285 147.8756 0)
			(effects
				(font
					(size 1.27 1.27)
				)
				(justify left)
				(hide yes)
			)
		)
	)
	(global_label "USR_LED3"
		(shape input)
		(at 255.27 114.935 0)
		(fields_autoplaced yes)
		(effects
			(font
				(size 1.27 1.27)
			)
			(justify left)
		)
		(property "Intersheetrefs" "${INTERSHEET_REFS}"
			(at 267.0285 114.8556 0)
			(effects
				(font
					(size 1.27 1.27)
				)
				(justify left)
				(hide yes)
			)
		)
	)
	(global_label "CA3_A"
		(shape input)
		(at 385.445 155.575 0)
		(fields_autoplaced yes)
		(effects
			(font
				(size 1.27 1.27)
			)
			(justify left)
		)
		(property "Intersheetrefs" "${INTERSHEET_REFS}"
			(at 393.3935 155.4956 0)
			(effects
				(font
					(size 1.27 1.27)
				)
				(justify left)
				(hide yes)
			)
		)
	)
	(global_label "SD_DAT1"
		(shape input)
		(at 170.815 145.415 180)
		(fields_autoplaced yes)
		(effects
			(font
				(size 1.27 1.27)
			)
			(justify right)
		)
		(property "Intersheetrefs" "${INTERSHEET_REFS}"
			(at 160.5079 145.3356 0)
			(effects
				(font
					(size 1.27 1.27)
				)
				(justify right)
				(hide yes)
			)
		)
	)
	(global_label "ETH_RX_CLK"
		(shape input)
		(at 170.815 99.695 180)
		(fields_autoplaced yes)
		(effects
			(font
				(size 1.27 1.27)
			)
			(justify right)
		)
		(property "Intersheetrefs" "${INTERSHEET_REFS}"
			(at 157.0608 99.6156 0)
			(effects
				(font
					(size 1.27 1.27)
				)
				(justify right)
				(hide yes)
			)
		)
	)
	(global_label "CKE0_A"
		(shape input)
		(at 384.81 86.995 0)
		(fields_autoplaced yes)
		(effects
			(font
				(size 1.27 1.27)
			)
			(justify left)
		)
		(property "Intersheetrefs" "${INTERSHEET_REFS}"
			(at 394.089 86.9156 0)
			(effects
				(font
					(size 1.27 1.27)
				)
				(justify left)
				(hide yes)
			)
		)
	)
	(global_label "DQ_S0_P"
		(shape input)
		(at 384.81 53.975 0)
		(fields_autoplaced yes)
		(effects
			(font
				(size 1.27 1.27)
			)
			(justify left)
		)
		(property "Intersheetrefs" "${INTERSHEET_REFS}"
			(at 395.359 53.8956 0)
			(effects
				(font
					(size 1.27 1.27)
				)
				(justify left)
				(hide yes)
			)
		)
	)
	(global_label "DQ_S1_P"
		(shape input)
		(at 384.81 114.935 0)
		(fields_autoplaced yes)
		(effects
			(font
				(size 1.27 1.27)
			)
			(justify left)
		)
		(property "Intersheetrefs" "${INTERSHEET_REFS}"
			(at 395.359 114.8556 0)
			(effects
				(font
					(size 1.27 1.27)
				)
				(justify left)
				(hide yes)
			)
		)
	)
	(global_label "VRN"
		(shape input)
		(at 310.515 216.535 180)
		(fields_autoplaced yes)
		(effects
			(font
				(size 1.27 1.27)
			)
			(justify right)
		)
		(property "Intersheetrefs" "${INTERSHEET_REFS}"
			(at 304.5018 216.4556 0)
			(effects
				(font
					(size 1.27 1.27)
				)
				(justify right)
				(hide yes)
			)
		)
	)
	(global_label "IO_P4"
		(shape input)
		(at 384.81 94.615 0)
		(fields_autoplaced yes)
		(effects
			(font
				(size 1.27 1.27)
			)
			(justify left)
		)
		(property "Intersheetrefs" "${INTERSHEET_REFS}"
			(at 392.5166 94.5356 0)
			(effects
				(font
					(size 1.27 1.27)
				)
				(justify left)
				(hide yes)
			)
		)
	)
	(global_label "EMCCLK"
		(shape input)
		(at 119.38 56.515 0)
		(fields_autoplaced yes)
		(effects
			(font
				(size 1.27 1.27)
			)
			(justify left)
		)
		(property "Intersheetrefs" "${INTERSHEET_REFS}"
			(at 129.1428 56.4356 0)
			(effects
				(font
					(size 1.27 1.27)
				)
				(justify left)
				(hide yes)
			)
		)
	)
	(global_label "DQ14_A"
		(shape input)
		(at 384.81 102.235 0)
		(fields_autoplaced yes)
		(effects
			(font
				(size 1.27 1.27)
			)
			(justify left)
		)
		(property "Intersheetrefs" "${INTERSHEET_REFS}"
			(at 394.2099 102.1556 0)
			(effects
				(font
					(size 1.27 1.27)
				)
				(justify left)
				(hide yes)
			)
		)
	)
	(global_label "GCLK100"
		(shape input)
		(at 76.2 233.68 0)
		(fields_autoplaced yes)
		(effects
			(font
				(size 1.27 1.27)
			)
			(justify left)
		)
		(property "Intersheetrefs" "${INTERSHEET_REFS}"
			(at 86.9909 233.6006 0)
			(effects
				(font
					(size 1.27 1.27)
				)
				(justify left)
				(hide yes)
			)
		)
	)
	(global_label "QSPI_DQ2"
		(shape input)
		(at 119.38 48.895 0)
		(fields_autoplaced yes)
		(effects
			(font
				(size 1.27 1.27)
			)
			(justify left)
		)
		(property "Intersheetrefs" "${INTERSHEET_REFS}"
			(at 130.8966 48.8156 0)
			(effects
				(font
					(size 1.27 1.27)
				)
				(justify left)
				(hide yes)
			)
		)
	)
	(global_label "DQ05_A"
		(shape input)
		(at 384.81 74.295 0)
		(fields_autoplaced yes)
		(effects
			(font
				(size 1.27 1.27)
			)
			(justify left)
		)
		(property "Intersheetrefs" "${INTERSHEET_REFS}"
			(at 394.2099 74.2156 0)
			(effects
				(font
					(size 1.27 1.27)
				)
				(justify left)
				(hide yes)
			)
		)
	)
	(global_label "USR_BTN4"
		(shape input)
		(at 255.27 86.995 0)
		(fields_autoplaced yes)
		(effects
			(font
				(size 1.27 1.27)
			)
			(justify left)
		)
		(property "Intersheetrefs" "${INTERSHEET_REFS}"
			(at 267.1494 86.9156 0)
			(effects
				(font
					(size 1.27 1.27)
				)
				(justify left)
				(hide yes)
			)
		)
	)
	(global_label "SD_DAT0"
		(shape input)
		(at 170.815 155.575 180)
		(fields_autoplaced yes)
		(effects
			(font
				(size 1.27 1.27)
			)
			(justify right)
		)
		(property "Intersheetrefs" "${INTERSHEET_REFS}"
			(at 160.5079 155.4956 0)
			(effects
				(font
					(size 1.27 1.27)
				)
				(justify right)
				(hide yes)
			)
		)
	)
	(global_label "QSPI_DQ3"
		(shape input)
		(at 119.38 51.435 0)
		(fields_autoplaced yes)
		(effects
			(font
				(size 1.27 1.27)
			)
			(justify left)
		)
		(property "Intersheetrefs" "${INTERSHEET_REFS}"
			(at 130.8966 51.3556 0)
			(effects
				(font
					(size 1.27 1.27)
				)
				(justify left)
				(hide yes)
			)
		)
	)
	(global_label "ETH_TX_EN"
		(shape input)
		(at 170.815 59.055 180)
		(fields_autoplaced yes)
		(effects
			(font
				(size 1.27 1.27)
			)
			(justify right)
		)
		(property "Intersheetrefs" "${INTERSHEET_REFS}"
			(at 158.4518 58.9756 0)
			(effects
				(font
					(size 1.27 1.27)
				)
				(justify right)
				(hide yes)
			)
		)
	)
	(global_label "IO_V4"
		(shape input)
		(at 384.81 109.855 0)
		(fields_autoplaced yes)
		(effects
			(font
				(size 1.27 1.27)
			)
			(justify left)
		)
		(property "Intersheetrefs" "${INTERSHEET_REFS}"
			(at 392.3352 109.7756 0)
			(effects
				(font
					(size 1.27 1.27)
				)
				(justify left)
				(hide yes)
			)
		)
	)
	(global_label "IO_W11"
		(shape input)
		(at 300.355 69.215 180)
		(fields_autoplaced yes)
		(effects
			(font
				(size 1.27 1.27)
			)
			(justify right)
		)
		(property "Intersheetrefs" "${INTERSHEET_REFS}"
			(at 291.2575 69.1356 0)
			(effects
				(font
					(size 1.27 1.27)
				)
				(justify right)
				(hide yes)
			)
		)
	)
	(global_label "DQ06_A"
		(shape input)
		(at 384.81 79.375 0)
		(fields_autoplaced yes)
		(effects
			(font
				(size 1.27 1.27)
			)
			(justify left)
		)
		(property "Intersheetrefs" "${INTERSHEET_REFS}"
			(at 394.2099 79.2956 0)
			(effects
				(font
					(size 1.27 1.27)
				)
				(justify left)
				(hide yes)
			)
		)
	)
	(global_label "IO_V3"
		(shape input)
		(at 384.81 125.095 0)
		(fields_autoplaced yes)
		(effects
			(font
				(size 1.27 1.27)
			)
			(justify left)
		)
		(property "Intersheetrefs" "${INTERSHEET_REFS}"
			(at 392.3352 125.0156 0)
			(effects
				(font
					(size 1.27 1.27)
				)
				(justify left)
				(hide yes)
			)
		)
	)
	(global_label "PUDC_B"
		(shape input)
		(at 119.38 53.975 0)
		(fields_autoplaced yes)
		(effects
			(font
				(size 1.27 1.27)
			)
			(justify left)
		)
		(property "Intersheetrefs" "${INTERSHEET_REFS}"
			(at 129.0823 53.8956 0)
			(effects
				(font
					(size 1.27 1.27)
				)
				(justify left)
				(hide yes)
			)
		)
	)
	(global_label "IO_N5"
		(shape input)
		(at 384.81 130.175 0)
		(fields_autoplaced yes)
		(effects
			(font
				(size 1.27 1.27)
			)
			(justify left)
		)
		(property "Intersheetrefs" "${INTERSHEET_REFS}"
			(at 392.5771 130.0956 0)
			(effects
				(font
					(size 1.27 1.27)
				)
				(justify left)
				(hide yes)
			)
		)
	)
	(global_label "UART0_RX"
		(shape input)
		(at 34.925 114.935 180)
		(fields_autoplaced yes)
		(effects
			(font
				(size 1.27 1.27)
			)
			(justify right)
		)
		(property "Intersheetrefs" "${INTERSHEET_REFS}"
			(at 23.2875 114.8556 0)
			(effects
				(font
					(size 1.27 1.27)
				)
				(justify right)
				(hide yes)
			)
		)
	)
	(global_label "DQ_S1_N"
		(shape input)
		(at 384.81 117.475 0)
		(fields_autoplaced yes)
		(effects
			(font
				(size 1.27 1.27)
			)
			(justify left)
		)
		(property "Intersheetrefs" "${INTERSHEET_REFS}"
			(at 395.4194 117.3956 0)
			(effects
				(font
					(size 1.27 1.27)
				)
				(justify left)
				(hide yes)
			)
		)
	)
	(global_label "HR_DQ3"
		(shape input)
		(at 34.925 150.495 180)
		(fields_autoplaced yes)
		(effects
			(font
				(size 1.27 1.27)
			)
			(justify right)
		)
		(property "Intersheetrefs" "${INTERSHEET_REFS}"
			(at 25.2227 150.4156 0)
			(effects
				(font
					(size 1.27 1.27)
				)
				(justify right)
				(hide yes)
			)
		)
	)
	(global_label "HR_DQ1"
		(shape input)
		(at 34.925 132.715 180)
		(fields_autoplaced yes)
		(effects
			(font
				(size 1.27 1.27)
			)
			(justify right)
		)
		(property "Intersheetrefs" "${INTERSHEET_REFS}"
			(at 25.2227 132.6356 0)
			(effects
				(font
					(size 1.27 1.27)
				)
				(justify right)
				(hide yes)
			)
		)
	)
	(global_label "HR_DQ0"
		(shape input)
		(at 34.925 158.115 180)
		(fields_autoplaced yes)
		(effects
			(font
				(size 1.27 1.27)
			)
			(justify right)
		)
		(property "Intersheetrefs" "${INTERSHEET_REFS}"
			(at 25.2227 158.0356 0)
			(effects
				(font
					(size 1.27 1.27)
				)
				(justify right)
				(hide yes)
			)
		)
	)
	(global_label "ETH_INT_N"
		(shape input)
		(at 170.815 76.835 180)
		(fields_autoplaced yes)
		(effects
			(font
				(size 1.27 1.27)
			)
			(justify right)
		)
		(property "Intersheetrefs" "${INTERSHEET_REFS}"
			(at 158.8751 76.7556 0)
			(effects
				(font
					(size 1.27 1.27)
				)
				(justify right)
				(hide yes)
			)
		)
	)
	(global_label "ETH_RXD0"
		(shape input)
		(at 170.815 79.375 180)
		(fields_autoplaced yes)
		(effects
			(font
				(size 1.27 1.27)
			)
			(justify right)
		)
		(property "Intersheetrefs" "${INTERSHEET_REFS}"
			(at 159.117 79.2956 0)
			(effects
				(font
					(size 1.27 1.27)
				)
				(justify right)
				(hide yes)
			)
		)
	)
	(global_label "ETH_RX_DV"
		(shape input)
		(at 170.815 81.915 180)
		(fields_autoplaced yes)
		(effects
			(font
				(size 1.27 1.27)
			)
			(justify right)
		)
		(property "Intersheetrefs" "${INTERSHEET_REFS}"
			(at 158.2703 81.8356 0)
			(effects
				(font
					(size 1.27 1.27)
				)
				(justify right)
				(hide yes)
			)
		)
	)
	(global_label "IO_U5"
		(shape input)
		(at 384.81 122.555 0)
		(fields_autoplaced yes)
		(effects
			(font
				(size 1.27 1.27)
			)
			(justify left)
		)
		(property "Intersheetrefs" "${INTERSHEET_REFS}"
			(at 392.5771 122.4756 0)
			(effects
				(font
					(size 1.27 1.27)
				)
				(justify left)
				(hide yes)
			)
		)
	)
	(global_label "ETH_RXD1"
		(shape input)
		(at 170.815 86.995 180)
		(fields_autoplaced yes)
		(effects
			(font
				(size 1.27 1.27)
			)
			(justify right)
		)
		(property "Intersheetrefs" "${INTERSHEET_REFS}"
			(at 159.117 86.9156 0)
			(effects
				(font
					(size 1.27 1.27)
				)
				(justify right)
				(hide yes)
			)
		)
	)
	(global_label "IO_AB11"
		(shape input)
		(at 300.355 142.875 180)
		(fields_autoplaced yes)
		(effects
			(font
				(size 1.27 1.27)
			)
			(justify right)
		)
		(property "Intersheetrefs" "${INTERSHEET_REFS}"
			(at 290.3503 142.7956 0)
			(effects
				(font
					(size 1.27 1.27)
				)
				(justify right)
				(hide yes)
			)
		)
	)
	(global_label "CK_A_P"
		(shape input)
		(at 384.81 145.415 0)
		(fields_autoplaced yes)
		(effects
			(font
				(size 1.27 1.27)
			)
			(justify left)
		)
		(property "Intersheetrefs" "${INTERSHEET_REFS}"
			(at 393.968 145.3356 0)
			(effects
				(font
					(size 1.27 1.27)
				)
				(justify left)
				(hide yes)
			)
		)
	)
	(global_label "VRN"
		(shape input)
		(at 384.81 41.275 0)
		(fields_autoplaced yes)
		(effects
			(font
				(size 1.27 1.27)
			)
			(justify left)
		)
		(property "Intersheetrefs" "${INTERSHEET_REFS}"
			(at 390.8232 41.1956 0)
			(effects
				(font
					(size 1.27 1.27)
				)
				(justify left)
				(hide yes)
			)
		)
	)
	(global_label "DQ03_A"
		(shape input)
		(at 384.81 59.055 0)
		(fields_autoplaced yes)
		(effects
			(font
				(size 1.27 1.27)
			)
			(justify left)
		)
		(property "Intersheetrefs" "${INTERSHEET_REFS}"
			(at 394.2099 58.9756 0)
			(effects
				(font
					(size 1.27 1.27)
				)
				(justify left)
				(hide yes)
			)
		)
	)
	(global_label "HR_RW"
		(shape input)
		(at 34.925 112.395 180)
		(fields_autoplaced yes)
		(effects
			(font
				(size 1.27 1.27)
			)
			(justify right)
		)
		(property "Intersheetrefs" "${INTERSHEET_REFS}"
			(at 26.3113 112.3156 0)
			(effects
				(font
					(size 1.27 1.27)
				)
				(justify right)
				(hide yes)
			)
		)
	)
	(global_label "CS0_A"
		(shape input)
		(at 384.81 64.135 0)
		(fields_autoplaced yes)
		(effects
			(font
				(size 1.27 1.27)
			)
			(justify left)
		)
		(property "Intersheetrefs" "${INTERSHEET_REFS}"
			(at 392.8794 64.0556 0)
			(effects
				(font
					(size 1.27 1.27)
				)
				(justify left)
				(hide yes)
			)
		)
	)
	(global_label "SD_CD"
		(shape input)
		(at 170.815 147.955 180)
		(fields_autoplaced yes)
		(effects
			(font
				(size 1.27 1.27)
			)
			(justify right)
		)
		(property "Intersheetrefs" "${INTERSHEET_REFS}"
			(at 162.5037 147.8756 0)
			(effects
				(font
					(size 1.27 1.27)
				)
				(justify right)
				(hide yes)
			)
		)
	)
	(global_label "IO_R4"
		(shape input)
		(at 384.81 97.155 0)
		(fields_autoplaced yes)
		(effects
			(font
				(size 1.27 1.27)
			)
			(justify left)
		)
		(property "Intersheetrefs" "${INTERSHEET_REFS}"
			(at 392.5166 97.0756 0)
			(effects
				(font
					(size 1.27 1.27)
				)
				(justify left)
				(hide yes)
			)
		)
	)
	(global_label "DQ00_A"
		(shape input)
		(at 384.81 51.435 0)
		(fields_autoplaced yes)
		(effects
			(font
				(size 1.27 1.27)
			)
			(justify left)
		)
		(property "Intersheetrefs" "${INTERSHEET_REFS}"
			(at 394.2099 51.3556 0)
			(effects
				(font
					(size 1.27 1.27)
				)
				(justify left)
				(hide yes)
			)
		)
	)
	(global_label "QSPI_DQ1"
		(shape input)
		(at 119.38 46.355 0)
		(fields_autoplaced yes)
		(effects
			(font
				(size 1.27 1.27)
			)
			(justify left)
		)
		(property "Intersheetrefs" "${INTERSHEET_REFS}"
			(at 130.8966 46.2756 0)
			(effects
				(font
					(size 1.27 1.27)
				)
				(justify left)
				(hide yes)
			)
		)
	)
	(global_label "IO_Y11"
		(shape input)
		(at 300.355 71.755 180)
		(fields_autoplaced yes)
		(effects
			(font
				(size 1.27 1.27)
			)
			(justify right)
		)
		(property "Intersheetrefs" "${INTERSHEET_REFS}"
			(at 291.6203 71.6756 0)
			(effects
				(font
					(size 1.27 1.27)
				)
				(justify right)
				(hide yes)
			)
		)
	)
	(global_label "QSPI_DQ0"
		(shape input)
		(at 119.38 43.815 0)
		(fields_autoplaced yes)
		(effects
			(font
				(size 1.27 1.27)
			)
			(justify left)
		)
		(property "Intersheetrefs" "${INTERSHEET_REFS}"
			(at 130.8966 43.7356 0)
			(effects
				(font
					(size 1.27 1.27)
				)
				(justify left)
				(hide yes)
			)
		)
	)
	(global_label "DQ10_A"
		(shape input)
		(at 384.81 150.495 0)
		(fields_autoplaced yes)
		(effects
			(font
				(size 1.27 1.27)
			)
			(justify left)
		)
		(property "Intersheetrefs" "${INTERSHEET_REFS}"
			(at 394.2099 150.4156 0)
			(effects
				(font
					(size 1.27 1.27)
				)
				(justify left)
				(hide yes)
			)
		)
	)
	(global_label "VREF_34"
		(shape input)
		(at 369.57 224.79 0)
		(fields_autoplaced yes)
		(effects
			(font
				(size 1.27 1.27)
			)
			(justify left)
		)
		(property "Intersheetrefs" "${INTERSHEET_REFS}"
			(at 379.8771 224.7106 0)
			(effects
				(font
					(size 1.27 1.27)
				)
				(justify left)
				(hide yes)
			)
		)
	)
	(global_label "ETH_TXD2"
		(shape input)
		(at 170.815 142.875 180)
		(fields_autoplaced yes)
		(effects
			(font
				(size 1.27 1.27)
			)
			(justify right)
		)
		(property "Intersheetrefs" "${INTERSHEET_REFS}"
			(at 159.4194 142.7956 0)
			(effects
				(font
					(size 1.27 1.27)
				)
				(justify right)
				(hide yes)
			)
		)
	)
	(global_label "IO_T4"
		(shape input)
		(at 384.81 104.775 0)
		(fields_autoplaced yes)
		(effects
			(font
				(size 1.27 1.27)
			)
			(justify left)
		)
		(property "Intersheetrefs" "${INTERSHEET_REFS}"
			(at 392.2142 104.6956 0)
			(effects
				(font
					(size 1.27 1.27)
				)
				(justify left)
				(hide yes)
			)
		)
	)
	(global_label "ETH_REF_CLK"
		(shape input)
		(at 170.815 48.895 180)
		(fields_autoplaced yes)
		(effects
			(font
				(size 1.27 1.27)
			)
			(justify right)
		)
		(property "Intersheetrefs" "${INTERSHEET_REFS}"
			(at 156.0327 48.8156 0)
			(effects
				(font
					(size 1.27 1.27)
				)
				(justify right)
				(hide yes)
			)
		)
	)
	(global_label "DQ_S0_N"
		(shape input)
		(at 384.81 56.515 0)
		(fields_autoplaced yes)
		(effects
			(font
				(size 1.27 1.27)
			)
			(justify left)
		)
		(property "Intersheetrefs" "${INTERSHEET_REFS}"
			(at 395.4194 56.4356 0)
			(effects
				(font
					(size 1.27 1.27)
				)
				(justify left)
				(hide yes)
			)
		)
	)
	(global_label "DQ02_A"
		(shape input)
		(at 384.81 48.895 0)
		(fields_autoplaced yes)
		(effects
			(font
				(size 1.27 1.27)
			)
			(justify left)
		)
		(property "Intersheetrefs" "${INTERSHEET_REFS}"
			(at 394.2099 48.8156 0)
			(effects
				(font
					(size 1.27 1.27)
				)
				(justify left)
				(hide yes)
			)
		)
	)
	(global_label "USR_BTN1"
		(shape input)
		(at 255.27 127.635 0)
		(fields_autoplaced yes)
		(effects
			(font
				(size 1.27 1.27)
			)
			(justify left)
		)
		(property "Intersheetrefs" "${INTERSHEET_REFS}"
			(at 267.1494 127.5556 0)
			(effects
				(font
					(size 1.27 1.27)
				)
				(justify left)
				(hide yes)
			)
		)
	)
	(global_label "ETH_TXD0"
		(shape input)
		(at 170.815 163.195 180)
		(fields_autoplaced yes)
		(effects
			(font
				(size 1.27 1.27)
			)
			(justify right)
		)
		(property "Intersheetrefs" "${INTERSHEET_REFS}"
			(at 159.4194 163.1156 0)
			(effects
				(font
					(size 1.27 1.27)
				)
				(justify right)
				(hide yes)
			)
		)
	)
	(global_label "AUX_JTAG_RST"
		(shape input)
		(at 34.925 127.635 180)
		(fields_autoplaced yes)
		(effects
			(font
				(size 1.27 1.27)
			)
			(justify right)
		)
		(property "Intersheetrefs" "${INTERSHEET_REFS}"
			(at 19.296 127.5556 0)
			(effects
				(font
					(size 1.27 1.27)
				)
				(justify right)
				(hide yes)
			)
		)
	)
	(global_label "TMDS_D1_P"
		(shape input)
		(at 119.38 120.015 0)
		(fields_autoplaced yes)
		(effects
			(font
				(size 1.27 1.27)
			)
			(justify left)
		)
		(property "Intersheetrefs" "${INTERSHEET_REFS}"
			(at 132.2875 119.9356 0)
			(effects
				(font
					(size 1.27 1.27)
				)
				(justify left)
				(hide yes)
			)
		)
	)
	(global_label "ETH_RXD2"
		(shape input)
		(at 170.815 84.455 180)
		(fields_autoplaced yes)
		(effects
			(font
				(size 1.27 1.27)
			)
			(justify right)
		)
		(property "Intersheetrefs" "${INTERSHEET_REFS}"
			(at 159.117 84.3756 0)
			(effects
				(font
					(size 1.27 1.27)
				)
				(justify right)
				(hide yes)
			)
		)
	)
	(global_label "AUX_JTAG_TCK"
		(shape input)
		(at 34.925 61.595 180)
		(fields_autoplaced yes)
		(effects
			(font
				(size 1.27 1.27)
			)
			(justify right)
		)
		(property "Intersheetrefs" "${INTERSHEET_REFS}"
			(at 19.2356 61.5156 0)
			(effects
				(font
					(size 1.27 1.27)
				)
				(justify right)
				(hide yes)
			)
		)
	)
	(global_label "FPGA_AA21_BALL"
		(shape input)
		(at 33.655 84.455 180)
		(fields_autoplaced yes)
		(effects
			(font
				(size 1.27 1.27)
			)
			(justify right)
		)
		(property "Intersheetrefs" "${INTERSHEET_REFS}"
			(at 15.6675 84.3756 0)
			(effects
				(font
					(size 1.27 1.27)
				)
				(justify right)
				(hide yes)
			)
		)
	)
	(global_label "GCLK100"
		(shape input)
		(at 119.38 99.695 0)
		(fields_autoplaced yes)
		(effects
			(font
				(size 1.27 1.27)
			)
			(justify left)
		)
		(property "Intersheetrefs" "${INTERSHEET_REFS}"
			(at 130.1709 99.6156 0)
			(effects
				(font
					(size 1.27 1.27)
				)
				(justify left)
				(hide yes)
			)
		)
	)
	(global_label "FPGA_AB22_BALL"
		(shape input)
		(at 33.655 86.995 180)
		(fields_autoplaced yes)
		(effects
			(font
				(size 1.27 1.27)
			)
			(justify right)
		)
		(property "Intersheetrefs" "${INTERSHEET_REFS}"
			(at 15.486 86.9156 0)
			(effects
				(font
					(size 1.27 1.27)
				)
				(justify right)
				(hide yes)
			)
		)
	)
	(global_label "HR_DQ2"
		(shape input)
		(at 34.925 130.175 180)
		(fields_autoplaced yes)
		(effects
			(font
				(size 1.27 1.27)
			)
			(justify right)
		)
		(property "Intersheetrefs" "${INTERSHEET_REFS}"
			(at 25.2227 130.0956 0)
			(effects
				(font
					(size 1.27 1.27)
				)
				(justify right)
				(hide yes)
			)
		)
	)
	(global_label "CA5_A"
		(shape input)
		(at 385.445 158.115 0)
		(fields_autoplaced yes)
		(effects
			(font
				(size 1.27 1.27)
			)
			(justify left)
		)
		(property "Intersheetrefs" "${INTERSHEET_REFS}"
			(at 393.3935 158.0356 0)
			(effects
				(font
					(size 1.27 1.27)
				)
				(justify left)
				(hide yes)
			)
		)
	)
	(global_label "UART1_TX"
		(shape input)
		(at 33.655 79.375 180)
		(fields_autoplaced yes)
		(effects
			(font
				(size 1.27 1.27)
			)
			(justify right)
		)
		(property "Intersheetrefs" "${INTERSHEET_REFS}"
			(at 22.3198 79.2956 0)
			(effects
				(font
					(size 1.27 1.27)
				)
				(justify right)
				(hide yes)
			)
		)
	)
	(global_label "IO_W4"
		(shape input)
		(at 384.81 112.395 0)
		(fields_autoplaced yes)
		(effects
			(font
				(size 1.27 1.27)
			)
			(justify left)
		)
		(property "Intersheetrefs" "${INTERSHEET_REFS}"
			(at 392.698 112.3156 0)
			(effects
				(font
					(size 1.27 1.27)
				)
				(justify left)
				(hide yes)
			)
		)
	)
	(global_label "DQ09_A"
		(shape input)
		(at 384.81 142.875 0)
		(fields_autoplaced yes)
		(effects
			(font
				(size 1.27 1.27)
			)
			(justify left)
		)
		(property "Intersheetrefs" "${INTERSHEET_REFS}"
			(at 394.2099 142.7956 0)
			(effects
				(font
					(size 1.27 1.27)
				)
				(justify left)
				(hide yes)
			)
		)
	)
	(global_label "VDDQ"
		(shape input)
		(at 326.39 216.535 0)
		(fields_autoplaced yes)
		(effects
			(font
				(size 1.27 1.27)
			)
			(justify left)
		)
		(property "Intersheetrefs" "${INTERSHEET_REFS}"
			(at 333.6732 216.4556 0)
			(effects
				(font
					(size 1.27 1.27)
				)
				(justify left)
				(hide yes)
			)
		)
	)
	(global_label "ETH_TXD3"
		(shape input)
		(at 170.815 92.075 180)
		(fields_autoplaced yes)
		(effects
			(font
				(size 1.27 1.27)
			)
			(justify right)
		)
		(property "Intersheetrefs" "${INTERSHEET_REFS}"
			(at 159.4194 91.9956 0)
			(effects
				(font
					(size 1.27 1.27)
				)
				(justify right)
				(hide yes)
			)
		)
	)
	(global_label "UART0_TX"
		(shape input)
		(at 34.925 117.475 180)
		(fields_autoplaced yes)
		(effects
			(font
				(size 1.27 1.27)
			)
			(justify right)
		)
		(property "Intersheetrefs" "${INTERSHEET_REFS}"
			(at 23.5898 117.3956 0)
			(effects
				(font
					(size 1.27 1.27)
				)
				(justify right)
				(hide yes)
			)
		)
	)
	(global_label "FCS_B"
		(shape input)
		(at 119.38 69.215 0)
		(fields_autoplaced yes)
		(effects
			(font
				(size 1.27 1.27)
			)
			(justify left)
		)
		(property "Intersheetrefs" "${INTERSHEET_REFS}"
			(at 127.5099 69.1356 0)
			(effects
				(font
					(size 1.27 1.27)
				)
				(justify left)
				(hide yes)
			)
		)
	)
	(global_label "SD_CLK"
		(shape input)
		(at 170.815 158.115 180)
		(fields_autoplaced yes)
		(effects
			(font
				(size 1.27 1.27)
			)
			(justify right)
		)
		(property "Intersheetrefs" "${INTERSHEET_REFS}"
			(at 161.4756 158.0356 0)
			(effects
				(font
					(size 1.27 1.27)
				)
				(justify right)
				(hide yes)
			)
		)
	)
	(symbol
		(lib_id "antmicroResistors0603:R_1k_0603")
		(at 343.535 218.44 270)
		(unit 1)
		(exclude_from_sim no)
		(in_bom yes)
		(on_board yes)
		(dnp no)
		(property "Reference" "R5"
			(at 344.805 220.98 90)
			(effects
				(font
					(size 1.27 1.27)
					(thickness 0.15)
				)
				(justify left bottom)
			)
		)
		(property "Value" "R_1k_0603"
			(at 330.835 238.76 0)
			(effects
				(font
					(size 1.27 1.27)
					(thickness 0.15)
				)
				(justify left bottom)
				(hide yes)
			)
		)
		(property "Footprint" "antmicro-footprints:R_0603_1608Metric"
			(at 328.295 238.76 0)
			(effects
				(font
					(size 1.27 1.27)
					(thickness 0.15)
				)
				(justify left bottom)
				(hide yes)
			)
		)
		(property "Datasheet" "https://www.bourns.com/docs/product-datasheets/cr.pdf"
			(at 325.755 238.76 0)
			(effects
				(font
					(size 1.27 1.27)
					(thickness 0.15)
				)
				(justify left bottom)
				(hide yes)
			)
		)
		(property "Description" ""
			(at 343.535 218.44 0)
			(effects
				(font
					(size 1.27 1.27)
				)
			)
		)
		(property "Manufacturer" "Bourns"
			(at 320.675 238.76 0)
			(effects
				(font
					(size 1.27 1.27)
					(thickness 0.15)
				)
				(justify left bottom)
				(hide yes)
			)
		)
		(property "MPN" "CR0603-FX-1001ELF"
			(at 323.215 238.76 0)
			(effects
				(font
					(size 1.27 1.27)
					(thickness 0.15)
				)
				(justify left bottom)
				(hide yes)
			)
		)
		(property "Val" "1k"
			(at 344.805 222.8849 90)
			(effects
				(font
					(size 1.27 1.27)
					(thickness 0.15)
				)
				(justify left bottom)
			)
		)
		(property "License" "Apache-2.0"
			(at 318.135 238.76 0)
			(effects
				(font
					(size 1.27 1.27)
					(thickness 0.15)
				)
				(justify left bottom)
				(hide yes)
			)
		)
		(property "Author" "Antmicro"
			(at 315.595 238.76 0)
			(effects
				(font
					(size 1.27 1.27)
					(thickness 0.15)
				)
				(justify left bottom)
				(hide yes)
			)
		)
		(property "Tolerance" "1%"
			(at 333.375 238.76 0)
			(effects
				(font
					(size 1.27 1.27)
				)
				(justify left bottom)
				(hide yes)
			)
		)
		(pin "1"
		)
		(pin "2"
		)
		(instances
			(project "lpddr4-test-board"
				(path ""
					(reference "R5")
					(unit 1)
				)
			)
		)
	)
	(symbol
		(lib_id "antmicroResistors0603:R_1k_0603")
		(at 343.535 226.06 270)
		(unit 1)
		(exclude_from_sim no)
		(in_bom yes)
		(on_board yes)
		(dnp no)
		(property "Reference" "R6"
			(at 344.805 228.6 90)
			(effects
				(font
					(size 1.27 1.27)
					(thickness 0.15)
				)
				(justify left bottom)
			)
		)
		(property "Value" "R_1k_0603"
			(at 330.835 246.38 0)
			(effects
				(font
					(size 1.27 1.27)
					(thickness 0.15)
				)
				(justify left bottom)
				(hide yes)
			)
		)
		(property "Footprint" "antmicro-footprints:R_0603_1608Metric"
			(at 328.295 246.38 0)
			(effects
				(font
					(size 1.27 1.27)
					(thickness 0.15)
				)
				(justify left bottom)
				(hide yes)
			)
		)
		(property "Datasheet" "https://www.bourns.com/docs/product-datasheets/cr.pdf"
			(at 325.755 246.38 0)
			(effects
				(font
					(size 1.27 1.27)
					(thickness 0.15)
				)
				(justify left bottom)
				(hide yes)
			)
		)
		(property "Description" ""
			(at 343.535 226.06 0)
			(effects
				(font
					(size 1.27 1.27)
				)
			)
		)
		(property "Manufacturer" "Bourns"
			(at 320.675 246.38 0)
			(effects
				(font
					(size 1.27 1.27)
					(thickness 0.15)
				)
				(justify left bottom)
				(hide yes)
			)
		)
		(property "MPN" "CR0603-FX-1001ELF"
			(at 323.215 246.38 0)
			(effects
				(font
					(size 1.27 1.27)
					(thickness 0.15)
				)
				(justify left bottom)
				(hide yes)
			)
		)
		(property "Val" "1k"
			(at 344.805 230.5049 90)
			(effects
				(font
					(size 1.27 1.27)
					(thickness 0.15)
				)
				(justify left bottom)
			)
		)
		(property "License" "Apache-2.0"
			(at 318.135 246.38 0)
			(effects
				(font
					(size 1.27 1.27)
					(thickness 0.15)
				)
				(justify left bottom)
				(hide yes)
			)
		)
		(property "Author" "Antmicro"
			(at 315.595 246.38 0)
			(effects
				(font
					(size 1.27 1.27)
					(thickness 0.15)
				)
				(justify left bottom)
				(hide yes)
			)
		)
		(property "Tolerance" "1%"
			(at 333.375 246.38 0)
			(effects
				(font
					(size 1.27 1.27)
				)
				(justify left bottom)
				(hide yes)
			)
		)
		(pin "1"
		)
		(pin "2"
		)
		(instances
			(project "lpddr4-test-board"
				(path ""
					(reference "R6")
					(unit 1)
				)
			)
		)
	)
	(symbol
		(lib_id "antmicropower:GND")
		(at 343.535 232.41 0)
		(mirror y)
		(unit 1)
		(exclude_from_sim no)
		(in_bom yes)
		(on_board yes)
		(dnp no)
		(property "Reference" "#PWR09"
			(at 334.645 234.95 0)
			(effects
				(font
					(size 1.27 1.27)
					(thickness 0.15)
				)
				(justify left bottom)
				(hide yes)
			)
		)
		(property "Value" "GND"
			(at 341.63 236.855 0)
			(effects
				(font
					(size 1.27 1.27)
					(thickness 0.15)
				)
				(justify right bottom)
			)
		)
		(property "Footprint" ""
			(at 334.645 240.03 0)
			(effects
				(font
					(size 1.27 1.27)
					(thickness 0.15)
				)
				(justify left bottom)
				(hide yes)
			)
		)
		(property "Datasheet" ""
			(at 334.645 245.11 0)
			(effects
				(font
					(size 1.27 1.27)
					(thickness 0.15)
				)
				(justify left bottom)
				(hide yes)
			)
		)
		(property "Description" ""
			(at 343.535 232.41 0)
			(effects
				(font
					(size 1.27 1.27)
				)
			)
		)
		(property "Author" "Antmicro"
			(at 334.645 240.03 0)
			(effects
				(font
					(size 1.27 1.27)
					(thickness 0.15)
				)
				(justify left bottom)
				(hide yes)
			)
		)
		(property "License" "Apache-2.0"
			(at 334.645 242.57 0)
			(effects
				(font
					(size 1.27 1.27)
					(thickness 0.15)
				)
				(justify left bottom)
				(hide yes)
			)
		)
		(pin "1"
		)
		(instances
			(project "lpddr4-test-board"
				(path ""
					(reference "#PWR09")
					(unit 1)
				)
			)
		)
	)
	(symbol
		(lib_id "antmicroCapacitorsmisc:C_100n_6V3_0402")
		(at 355.6 231.14 270)
		(mirror x)
		(unit 1)
		(exclude_from_sim no)
		(in_bom yes)
		(on_board yes)
		(dnp no)
		(property "Reference" "C6"
			(at 356.235 227.965 90)
			(effects
				(font
					(size 1.27 1.27)
					(thickness 0.15)
				)
				(justify left top)
			)
		)
		(property "Value" "C_100n_6V3_0402"
			(at 345.44 210.82 0)
			(effects
				(font
					(size 1.27 1.27)
					(thickness 0.15)
				)
				(justify left bottom)
				(hide yes)
			)
		)
		(property "Footprint" "antmicro-footprints:C_0402_1005Metric"
			(at 342.9 210.82 0)
			(effects
				(font
					(size 1.27 1.27)
					(thickness 0.15)
				)
				(justify left bottom)
				(hide yes)
			)
		)
		(property "Datasheet" " "
			(at 340.36 210.82 0)
			(effects
				(font
					(size 1.27 1.27)
					(thickness 0.15)
				)
				(justify left bottom)
				(hide yes)
			)
		)
		(property "Description" ""
			(at 355.6 231.14 0)
			(effects
				(font
					(size 1.27 1.27)
				)
			)
		)
		(property "Manufacturer" "Walsin"
			(at 335.28 210.82 0)
			(effects
				(font
					(size 1.27 1.27)
					(thickness 0.15)
				)
				(justify left bottom)
				(hide yes)
			)
		)
		(property "MPN" "0402X104K6R3CT"
			(at 337.82 210.82 0)
			(effects
				(font
					(size 1.27 1.27)
					(thickness 0.15)
				)
				(justify left bottom)
				(hide yes)
			)
		)
		(property "Val" "100n"
			(at 356.235 231.775 90)
			(effects
				(font
					(size 1.27 1.27)
					(thickness 0.15)
				)
				(justify left top)
			)
		)
		(property "License" "Apache-2.0"
			(at 332.74 210.82 0)
			(effects
				(font
					(size 1.27 1.27)
					(thickness 0.15)
				)
				(justify left bottom)
				(hide yes)
			)
		)
		(property "Author" "Antmicro"
			(at 330.2 210.82 0)
			(effects
				(font
					(size 1.27 1.27)
					(thickness 0.15)
				)
				(justify left bottom)
				(hide yes)
			)
		)
		(property "Voltage" ""
			(at 327.66 210.82 0)
			(effects
				(font
					(size 1.27 1.27)
				)
				(justify left bottom)
				(hide yes)
			)
		)
		(property "Dielectric" ""
			(at 325.12 210.82 0)
			(effects
				(font
					(size 1.27 1.27)
				)
				(justify left bottom)
				(hide yes)
			)
		)
		(pin "1"
		)
		(pin "2"
		)
		(instances
			(project "lpddr4-test-board"
				(path ""
					(reference "C6")
					(unit 1)
				)
			)
		)
	)
	(symbol
		(lib_id "antmicroCapacitorsmisc:C_100n_6V3_0402")
		(at 365.76 231.14 270)
		(mirror x)
		(unit 1)
		(exclude_from_sim no)
		(in_bom yes)
		(on_board yes)
		(dnp no)
		(property "Reference" "C7"
			(at 366.395 227.965 90)
			(effects
				(font
					(size 1.27 1.27)
					(thickness 0.15)
				)
				(justify left top)
			)
		)
		(property "Value" "C_100n_6V3_0402"
			(at 355.6 210.82 0)
			(effects
				(font
					(size 1.27 1.27)
					(thickness 0.15)
				)
				(justify left bottom)
				(hide yes)
			)
		)
		(property "Footprint" "antmicro-footprints:C_0402_1005Metric"
			(at 353.06 210.82 0)
			(effects
				(font
					(size 1.27 1.27)
					(thickness 0.15)
				)
				(justify left bottom)
				(hide yes)
			)
		)
		(property "Datasheet" " "
			(at 350.52 210.82 0)
			(effects
				(font
					(size 1.27 1.27)
					(thickness 0.15)
				)
				(justify left bottom)
				(hide yes)
			)
		)
		(property "Description" ""
			(at 365.76 231.14 0)
			(effects
				(font
					(size 1.27 1.27)
				)
			)
		)
		(property "Manufacturer" "Walsin"
			(at 345.44 210.82 0)
			(effects
				(font
					(size 1.27 1.27)
					(thickness 0.15)
				)
				(justify left bottom)
				(hide yes)
			)
		)
		(property "MPN" "0402X104K6R3CT"
			(at 347.98 210.82 0)
			(effects
				(font
					(size 1.27 1.27)
					(thickness 0.15)
				)
				(justify left bottom)
				(hide yes)
			)
		)
		(property "Val" "100n"
			(at 366.395 231.775 90)
			(effects
				(font
					(size 1.27 1.27)
					(thickness 0.15)
				)
				(justify left top)
			)
		)
		(property "License" "Apache-2.0"
			(at 342.9 210.82 0)
			(effects
				(font
					(size 1.27 1.27)
					(thickness 0.15)
				)
				(justify left bottom)
				(hide yes)
			)
		)
		(property "Author" "Antmicro"
			(at 340.36 210.82 0)
			(effects
				(font
					(size 1.27 1.27)
					(thickness 0.15)
				)
				(justify left bottom)
				(hide yes)
			)
		)
		(property "Voltage" ""
			(at 337.82 210.82 0)
			(effects
				(font
					(size 1.27 1.27)
				)
				(justify left bottom)
				(hide yes)
			)
		)
		(property "Dielectric" ""
			(at 335.28 210.82 0)
			(effects
				(font
					(size 1.27 1.27)
				)
				(justify left bottom)
				(hide yes)
			)
		)
		(pin "1"
		)
		(pin "2"
		)
		(instances
			(project "lpddr4-test-board"
				(path ""
					(reference "C7")
					(unit 1)
				)
			)
		)
	)
	(symbol
		(lib_id "antmicropower:GND")
		(at 355.6 232.41 0)
		(mirror y)
		(unit 1)
		(exclude_from_sim no)
		(in_bom yes)
		(on_board yes)
		(dnp no)
		(property "Reference" "#PWR010"
			(at 346.71 234.95 0)
			(effects
				(font
					(size 1.27 1.27)
					(thickness 0.15)
				)
				(justify left bottom)
				(hide yes)
			)
		)
		(property "Value" "GND"
			(at 353.695 236.855 0)
			(effects
				(font
					(size 1.27 1.27)
					(thickness 0.15)
				)
				(justify right bottom)
			)
		)
		(property "Footprint" ""
			(at 346.71 240.03 0)
			(effects
				(font
					(size 1.27 1.27)
					(thickness 0.15)
				)
				(justify left bottom)
				(hide yes)
			)
		)
		(property "Datasheet" ""
			(at 346.71 245.11 0)
			(effects
				(font
					(size 1.27 1.27)
					(thickness 0.15)
				)
				(justify left bottom)
				(hide yes)
			)
		)
		(property "Description" ""
			(at 355.6 232.41 0)
			(effects
				(font
					(size 1.27 1.27)
				)
			)
		)
		(property "Author" "Antmicro"
			(at 346.71 240.03 0)
			(effects
				(font
					(size 1.27 1.27)
					(thickness 0.15)
				)
				(justify left bottom)
				(hide yes)
			)
		)
		(property "License" "Apache-2.0"
			(at 346.71 242.57 0)
			(effects
				(font
					(size 1.27 1.27)
					(thickness 0.15)
				)
				(justify left bottom)
				(hide yes)
			)
		)
		(pin "1"
		)
		(instances
			(project "lpddr4-test-board"
				(path ""
					(reference "#PWR010")
					(unit 1)
				)
			)
		)
	)
	(symbol
		(lib_id "antmicropower:GND")
		(at 365.76 232.41 0)
		(mirror y)
		(unit 1)
		(exclude_from_sim no)
		(in_bom yes)
		(on_board yes)
		(dnp no)
		(property "Reference" "#PWR011"
			(at 356.87 234.95 0)
			(effects
				(font
					(size 1.27 1.27)
					(thickness 0.15)
				)
				(justify left bottom)
				(hide yes)
			)
		)
		(property "Value" "GND"
			(at 363.855 236.855 0)
			(effects
				(font
					(size 1.27 1.27)
					(thickness 0.15)
				)
				(justify right bottom)
			)
		)
		(property "Footprint" ""
			(at 356.87 240.03 0)
			(effects
				(font
					(size 1.27 1.27)
					(thickness 0.15)
				)
				(justify left bottom)
				(hide yes)
			)
		)
		(property "Datasheet" ""
			(at 356.87 245.11 0)
			(effects
				(font
					(size 1.27 1.27)
					(thickness 0.15)
				)
				(justify left bottom)
				(hide yes)
			)
		)
		(property "Description" ""
			(at 365.76 232.41 0)
			(effects
				(font
					(size 1.27 1.27)
				)
			)
		)
		(property "Author" "Antmicro"
			(at 356.87 240.03 0)
			(effects
				(font
					(size 1.27 1.27)
					(thickness 0.15)
				)
				(justify left bottom)
				(hide yes)
			)
		)
		(property "License" "Apache-2.0"
			(at 356.87 242.57 0)
			(effects
				(font
					(size 1.27 1.27)
					(thickness 0.15)
				)
				(justify left bottom)
				(hide yes)
			)
		)
		(pin "1"
		)
		(instances
			(project "lpddr4-test-board"
				(path ""
					(reference "#PWR011")
					(unit 1)
				)
			)
		)
	)
	(symbol
		(lib_id "antmicroResistors0603:R_120R_0603")
		(at 316.23 216.535 0)
		(unit 1)
		(exclude_from_sim no)
		(in_bom yes)
		(on_board yes)
		(dnp no)
		(property "Reference" "R3"
			(at 321.31 216.535 0)
			(effects
				(font
					(size 1.27 1.27)
					(thickness 0.15)
				)
				(justify left bottom)
			)
		)
		(property "Value" "R_120R_0603"
			(at 336.55 229.235 0)
			(effects
				(font
					(size 1.27 1.27)
					(thickness 0.15)
				)
				(justify left bottom)
				(hide yes)
			)
		)
		(property "Footprint" "antmicro-footprints:R_0603_1608Metric"
			(at 336.55 231.775 0)
			(effects
				(font
					(size 1.27 1.27)
					(thickness 0.15)
				)
				(justify left bottom)
				(hide yes)
			)
		)
		(property "Datasheet" "https://www.bourns.com/docs/product-datasheets/cr.pdf"
			(at 336.55 234.315 0)
			(effects
				(font
					(size 1.27 1.27)
					(thickness 0.15)
				)
				(justify left bottom)
				(hide yes)
			)
		)
		(property "Description" ""
			(at 316.23 216.535 0)
			(effects
				(font
					(size 1.27 1.27)
				)
			)
		)
		(property "Manufacturer" "Bourns"
			(at 336.55 239.395 0)
			(effects
				(font
					(size 1.27 1.27)
					(thickness 0.15)
				)
				(justify left bottom)
				(hide yes)
			)
		)
		(property "MPN" "CR0603-FX-1200ELF"
			(at 336.55 236.855 0)
			(effects
				(font
					(size 1.27 1.27)
					(thickness 0.15)
				)
				(justify left bottom)
				(hide yes)
			)
		)
		(property "Val" "120R"
			(at 311.15 216.535 0)
			(effects
				(font
					(size 1.27 1.27)
					(thickness 0.15)
				)
				(justify left bottom)
			)
		)
		(property "License" "Apache-2.0"
			(at 336.55 241.935 0)
			(effects
				(font
					(size 1.27 1.27)
					(thickness 0.15)
				)
				(justify left bottom)
				(hide yes)
			)
		)
		(property "Author" "Antmicro"
			(at 336.55 244.475 0)
			(effects
				(font
					(size 1.27 1.27)
					(thickness 0.15)
				)
				(justify left bottom)
				(hide yes)
			)
		)
		(property "Tolerance" "1%"
			(at 336.55 226.695 0)
			(effects
				(font
					(size 1.27 1.27)
				)
				(justify left bottom)
				(hide yes)
			)
		)
		(pin "1"
		)
		(pin "2"
		)
		(instances
			(project "lpddr4-test-board"
				(path ""
					(reference "R3")
					(unit 1)
				)
			)
		)
	)
	(symbol
		(lib_id "antmicroResistors0603:R_120R_0603")
		(at 316.23 225.425 0)
		(unit 1)
		(exclude_from_sim no)
		(in_bom yes)
		(on_board yes)
		(dnp no)
		(property "Reference" "R4"
			(at 321.31 225.425 0)
			(effects
				(font
					(size 1.27 1.27)
					(thickness 0.15)
				)
				(justify left bottom)
			)
		)
		(property "Value" "R_120R_0603"
			(at 336.55 238.125 0)
			(effects
				(font
					(size 1.27 1.27)
					(thickness 0.15)
				)
				(justify left bottom)
				(hide yes)
			)
		)
		(property "Footprint" "antmicro-footprints:R_0603_1608Metric"
			(at 336.55 240.665 0)
			(effects
				(font
					(size 1.27 1.27)
					(thickness 0.15)
				)
				(justify left bottom)
				(hide yes)
			)
		)
		(property "Datasheet" "https://www.bourns.com/docs/product-datasheets/cr.pdf"
			(at 336.55 243.205 0)
			(effects
				(font
					(size 1.27 1.27)
					(thickness 0.15)
				)
				(justify left bottom)
				(hide yes)
			)
		)
		(property "Description" ""
			(at 316.23 225.425 0)
			(effects
				(font
					(size 1.27 1.27)
				)
			)
		)
		(property "Manufacturer" "Bourns"
			(at 336.55 248.285 0)
			(effects
				(font
					(size 1.27 1.27)
					(thickness 0.15)
				)
				(justify left bottom)
				(hide yes)
			)
		)
		(property "MPN" "CR0603-FX-1200ELF"
			(at 336.55 245.745 0)
			(effects
				(font
					(size 1.27 1.27)
					(thickness 0.15)
				)
				(justify left bottom)
				(hide yes)
			)
		)
		(property "Val" "120R"
			(at 311.15 225.425 0)
			(effects
				(font
					(size 1.27 1.27)
					(thickness 0.15)
				)
				(justify left bottom)
			)
		)
		(property "License" "Apache-2.0"
			(at 336.55 250.825 0)
			(effects
				(font
					(size 1.27 1.27)
					(thickness 0.15)
				)
				(justify left bottom)
				(hide yes)
			)
		)
		(property "Author" "Antmicro"
			(at 336.55 253.365 0)
			(effects
				(font
					(size 1.27 1.27)
					(thickness 0.15)
				)
				(justify left bottom)
				(hide yes)
			)
		)
		(property "Tolerance" "1%"
			(at 336.55 235.585 0)
			(effects
				(font
					(size 1.27 1.27)
				)
				(justify left bottom)
				(hide yes)
			)
		)
		(pin "1"
		)
		(pin "2"
		)
		(instances
			(project "lpddr4-test-board"
				(path ""
					(reference "R4")
					(unit 1)
				)
			)
		)
	)
	(symbol
		(lib_id "antmicropower:GND")
		(at 328.93 227.965 0)
		(mirror y)
		(unit 1)
		(exclude_from_sim no)
		(in_bom yes)
		(on_board yes)
		(dnp no)
		(property "Reference" "#PWR08"
			(at 320.04 230.505 0)
			(effects
				(font
					(size 1.27 1.27)
					(thickness 0.15)
				)
				(justify left bottom)
				(hide yes)
			)
		)
		(property "Value" "GND"
			(at 327.025 232.41 0)
			(effects
				(font
					(size 1.27 1.27)
					(thickness 0.15)
				)
				(justify right bottom)
			)
		)
		(property "Footprint" ""
			(at 320.04 235.585 0)
			(effects
				(font
					(size 1.27 1.27)
					(thickness 0.15)
				)
				(justify left bottom)
				(hide yes)
			)
		)
		(property "Datasheet" ""
			(at 320.04 240.665 0)
			(effects
				(font
					(size 1.27 1.27)
					(thickness 0.15)
				)
				(justify left bottom)
				(hide yes)
			)
		)
		(property "Description" ""
			(at 328.93 227.965 0)
			(effects
				(font
					(size 1.27 1.27)
				)
			)
		)
		(property "Author" "Antmicro"
			(at 320.04 235.585 0)
			(effects
				(font
					(size 1.27 1.27)
					(thickness 0.15)
				)
				(justify left bottom)
				(hide yes)
			)
		)
		(property "License" "Apache-2.0"
			(at 320.04 238.125 0)
			(effects
				(font
					(size 1.27 1.27)
					(thickness 0.15)
				)
				(justify left bottom)
				(hide yes)
			)
		)
		(pin "1"
		)
		(instances
			(project "lpddr4-test-board"
				(path ""
					(reference "#PWR08")
					(unit 1)
				)
			)
		)
	)
	(symbol
		(lib_id "antmicroCapacitorsmisc:C_100n_6V3_0402")
		(at 93.98 238.76 270)
		(mirror x)
		(unit 1)
		(exclude_from_sim no)
		(in_bom yes)
		(on_board yes)
		(dnp no)
		(property "Reference" "C5"
			(at 94.615 235.585 90)
			(effects
				(font
					(size 1.27 1.27)
					(thickness 0.15)
				)
				(justify left top)
			)
		)
		(property "Value" "C_100n_6V3_0402"
			(at 83.82 218.44 0)
			(effects
				(font
					(size 1.27 1.27)
					(thickness 0.15)
				)
				(justify left bottom)
				(hide yes)
			)
		)
		(property "Footprint" "antmicro-footprints:C_0402_1005Metric"
			(at 81.28 218.44 0)
			(effects
				(font
					(size 1.27 1.27)
					(thickness 0.15)
				)
				(justify left bottom)
				(hide yes)
			)
		)
		(property "Datasheet" " "
			(at 78.74 218.44 0)
			(effects
				(font
					(size 1.27 1.27)
					(thickness 0.15)
				)
				(justify left bottom)
				(hide yes)
			)
		)
		(property "Description" ""
			(at 93.98 238.76 0)
			(effects
				(font
					(size 1.27 1.27)
				)
			)
		)
		(property "Manufacturer" "Walsin"
			(at 73.66 218.44 0)
			(effects
				(font
					(size 1.27 1.27)
					(thickness 0.15)
				)
				(justify left bottom)
				(hide yes)
			)
		)
		(property "MPN" "0402X104K6R3CT"
			(at 76.2 218.44 0)
			(effects
				(font
					(size 1.27 1.27)
					(thickness 0.15)
				)
				(justify left bottom)
				(hide yes)
			)
		)
		(property "Val" "100n"
			(at 94.615 239.395 90)
			(effects
				(font
					(size 1.27 1.27)
					(thickness 0.15)
				)
				(justify left top)
			)
		)
		(property "License" "Apache-2.0"
			(at 71.12 218.44 0)
			(effects
				(font
					(size 1.27 1.27)
					(thickness 0.15)
				)
				(justify left bottom)
				(hide yes)
			)
		)
		(property "Author" "Antmicro"
			(at 68.58 218.44 0)
			(effects
				(font
					(size 1.27 1.27)
					(thickness 0.15)
				)
				(justify left bottom)
				(hide yes)
			)
		)
		(property "Voltage" ""
			(at 66.04 218.44 0)
			(effects
				(font
					(size 1.27 1.27)
				)
				(justify left bottom)
				(hide yes)
			)
		)
		(property "Dielectric" ""
			(at 63.5 218.44 0)
			(effects
				(font
					(size 1.27 1.27)
				)
				(justify left bottom)
				(hide yes)
			)
		)
		(pin "1"
		)
		(pin "2"
		)
		(instances
			(project "lpddr4-test-board"
				(path ""
					(reference "C5")
					(unit 1)
				)
			)
		)
	)
	(symbol
		(lib_id "antmicropower:GND")
		(at 93.98 240.03 0)
		(mirror y)
		(unit 1)
		(exclude_from_sim no)
		(in_bom yes)
		(on_board yes)
		(dnp no)
		(property "Reference" "#PWR07"
			(at 85.09 242.57 0)
			(effects
				(font
					(size 1.27 1.27)
					(thickness 0.15)
				)
				(justify left bottom)
				(hide yes)
			)
		)
		(property "Value" "GND"
			(at 92.075 244.475 0)
			(effects
				(font
					(size 1.27 1.27)
					(thickness 0.15)
				)
				(justify right bottom)
			)
		)
		(property "Footprint" ""
			(at 85.09 247.65 0)
			(effects
				(font
					(size 1.27 1.27)
					(thickness 0.15)
				)
				(justify left bottom)
				(hide yes)
			)
		)
		(property "Datasheet" ""
			(at 85.09 252.73 0)
			(effects
				(font
					(size 1.27 1.27)
					(thickness 0.15)
				)
				(justify left bottom)
				(hide yes)
			)
		)
		(property "Description" ""
			(at 93.98 240.03 0)
			(effects
				(font
					(size 1.27 1.27)
				)
			)
		)
		(property "Author" "Antmicro"
			(at 85.09 247.65 0)
			(effects
				(font
					(size 1.27 1.27)
					(thickness 0.15)
				)
				(justify left bottom)
				(hide yes)
			)
		)
		(property "License" "Apache-2.0"
			(at 85.09 250.19 0)
			(effects
				(font
					(size 1.27 1.27)
					(thickness 0.15)
				)
				(justify left bottom)
				(hide yes)
			)
		)
		(pin "1"
		)
		(instances
			(project "lpddr4-test-board"
				(path ""
					(reference "#PWR07")
					(unit 1)
				)
			)
		)
	)
	(symbol
		(lib_id "antmicropower:GND")
		(at 50.8 241.3 0)
		(mirror y)
		(unit 1)
		(exclude_from_sim no)
		(in_bom yes)
		(on_board yes)
		(dnp no)
		(property "Reference" "#PWR06"
			(at 41.91 243.84 0)
			(effects
				(font
					(size 1.27 1.27)
					(thickness 0.15)
				)
				(justify left bottom)
				(hide yes)
			)
		)
		(property "Value" "GND"
			(at 48.895 245.745 0)
			(effects
				(font
					(size 1.27 1.27)
					(thickness 0.15)
				)
				(justify right bottom)
			)
		)
		(property "Footprint" ""
			(at 41.91 248.92 0)
			(effects
				(font
					(size 1.27 1.27)
					(thickness 0.15)
				)
				(justify left bottom)
				(hide yes)
			)
		)
		(property "Datasheet" ""
			(at 41.91 254 0)
			(effects
				(font
					(size 1.27 1.27)
					(thickness 0.15)
				)
				(justify left bottom)
				(hide yes)
			)
		)
		(property "Description" ""
			(at 50.8 241.3 0)
			(effects
				(font
					(size 1.27 1.27)
				)
			)
		)
		(property "Author" "Antmicro"
			(at 41.91 248.92 0)
			(effects
				(font
					(size 1.27 1.27)
					(thickness 0.15)
				)
				(justify left bottom)
				(hide yes)
			)
		)
		(property "License" "Apache-2.0"
			(at 41.91 251.46 0)
			(effects
				(font
					(size 1.27 1.27)
					(thickness 0.15)
				)
				(justify left bottom)
				(hide yes)
			)
		)
		(pin "1"
		)
		(instances
			(project "lpddr4-test-board"
				(path ""
					(reference "#PWR06")
					(unit 1)
				)
			)
		)
	)
	(symbol
		(lib_id "antmicroOscillators:Oscillator_100MHz_ASFL1")
		(at 54.61 233.68 0)
		(unit 1)
		(exclude_from_sim no)
		(in_bom yes)
		(on_board yes)
		(dnp no)
		(property "Reference" "U2"
			(at 63.5 227.965 0)
			(effects
				(font
					(size 1.27 1.27)
					(thickness 0.15)
				)
			)
		)
		(property "Value" "ASFL1-100.000MHZ-L-T"
			(at 90.17 241.3 0)
			(effects
				(font
					(size 1.27 1.27)
					(thickness 0.15)
				)
				(justify left bottom)
				(hide yes)
			)
		)
		(property "Footprint" "antmicro-footprints:Oscillator_SMD_Abracon_ASFL1-4Pin_5.0x3.2mm"
			(at 80.645 248.285 0)
			(effects
				(font
					(size 1.27 1.27)
					(thickness 0.15)
				)
				(justify left bottom)
				(hide yes)
			)
		)
		(property "Datasheet" "https://abracon.com/Oscillators/ASFL1.pdf"
			(at 80.645 250.825 0)
			(effects
				(font
					(size 1.27 1.27)
					(thickness 0.15)
				)
				(justify left bottom)
				(hide yes)
			)
		)
		(property "Description" ""
			(at 54.61 233.68 0)
			(effects
				(font
					(size 1.27 1.27)
				)
			)
		)
		(property "Manufacturer" "Abracon"
			(at 80.645 240.665 0)
			(effects
				(font
					(size 1.27 1.27)
					(thickness 0.15)
				)
				(justify left bottom)
				(hide yes)
			)
		)
		(property "MPN" "ASFL1-100.000MHZ-L-T"
			(at 53.34 230.505 0)
			(effects
				(font
					(size 1.27 1.27)
					(thickness 0.15)
				)
				(justify left bottom)
			)
		)
		(property "Author" "Antmicro"
			(at 80.645 253.365 0)
			(effects
				(font
					(size 1.27 1.27)
					(thickness 0.15)
				)
				(justify left bottom)
				(hide yes)
			)
		)
		(property "License" "Apache-2.0"
			(at 80.645 255.905 0)
			(effects
				(font
					(size 1.27 1.27)
					(thickness 0.15)
				)
				(justify left bottom)
				(hide yes)
			)
		)
		(property "Val" "100 MHz"
			(at 59.69 243.205 0)
			(effects
				(font
					(size 1.27 1.27)
					(thickness 0.15)
				)
				(justify left bottom)
			)
		)
		(pin "1"
		)
		(pin "2"
		)
		(pin "3"
		)
		(pin "4"
		)
		(instances
			(project "lpddr4-test-board"
				(path ""
					(reference "U2")
					(unit 1)
				)
			)
		)
	)
	(symbol
		(lib_id "antmicroFPGAChips:XC7K70T-FBG484")
		(at 382.27 41.275 0)
		(mirror y)
		(unit 4)
		(exclude_from_sim no)
		(in_bom yes)
		(on_board yes)
		(dnp no)
		(property "Reference" "U3"
			(at 377.19 33.02 0)
			(effects
				(font
					(size 1.27 1.27)
					(thickness 0.15)
				)
				(justify left bottom)
			)
		)
		(property "Value" "XC7K70T-FBG484"
			(at 328.93 46.355 0)
			(effects
				(font
					(size 1.27 1.27)
					(thickness 0.15)
				)
				(justify left bottom)
				(hide yes)
			)
		)
		(property "Footprint" "antmicro-footprints:BGA-484_23x23mm_Layout22x22_P1mm_FBG484"
			(at 328.93 48.895 0)
			(effects
				(font
					(size 1.27 1.27)
					(thickness 0.15)
				)
				(justify left bottom)
				(hide yes)
			)
		)
		(property "Datasheet" "https://docs.xilinx.com/v/u/en-US/ds182_Kintex_7_Data_Sheet"
			(at 328.93 51.435 0)
			(effects
				(font
					(size 1.27 1.27)
					(thickness 0.15)
				)
				(justify left bottom)
				(hide yes)
			)
		)
		(property "Description" ""
			(at 382.27 41.275 0)
			(effects
				(font
					(size 1.27 1.27)
				)
			)
		)
		(property "Manufacturer" "AMD-Xilinx"
			(at 328.93 53.975 0)
			(effects
				(font
					(size 1.27 1.27)
					(thickness 0.15)
				)
				(justify left bottom)
				(hide yes)
			)
		)
		(property "MPN" "XC7K70T-1FBG484C"
			(at 327.66 35.56 0)
			(effects
				(font
					(size 1.27 1.27)
					(thickness 0.15)
				)
				(justify left bottom)
			)
		)
		(property "Author" "Antmicro"
			(at 328.93 56.515 0)
			(effects
				(font
					(size 1.27 1.27)
					(thickness 0.15)
				)
				(justify left bottom)
				(hide yes)
			)
		)
		(property "License" "Apache-2.0"
			(at 328.93 59.055 0)
			(effects
				(font
					(size 1.27 1.27)
					(thickness 0.15)
				)
				(justify left bottom)
				(hide yes)
			)
		)
		(pin "AA1"
		)
		(pin "AA3"
		)
		(pin "AA4"
		)
		(pin "AB1"
		)
		(pin "AB2"
		)
		(pin "AB3"
		)
		(pin "K1"
		)
		(pin "K2"
		)
		(pin "K3"
		)
		(pin "K4"
		)
		(pin "L1"
		)
		(pin "L3"
		)
		(pin "L4"
		)
		(pin "L5"
		)
		(pin "M1"
		)
		(pin "M2"
		)
		(pin "M3"
		)
		(pin "M5"
		)
		(pin "N2"
		)
		(pin "N3"
		)
		(pin "N4"
		)
		(pin "N5"
		)
		(pin "P1"
		)
		(pin "P2"
		)
		(pin "P4"
		)
		(pin "P5"
		)
		(pin "R1"
		)
		(pin "R2"
		)
		(pin "R3"
		)
		(pin "R4"
		)
		(pin "T1"
		)
		(pin "T3"
		)
		(pin "T4"
		)
		(pin "T5"
		)
		(pin "U1"
		)
		(pin "U2"
		)
		(pin "U3"
		)
		(pin "U5"
		)
		(pin "V2"
		)
		(pin "V3"
		)
		(pin "V4"
		)
		(pin "V5"
		)
		(pin "W1"
		)
		(pin "W2"
		)
		(pin "W4"
		)
		(pin "W5"
		)
		(pin "Y1"
		)
		(pin "Y2"
		)
		(pin "Y3"
		)
		(pin "Y4"
		)
		(pin "R20"
		)
		(pin "R5"
		)
		(pin "R8"
		)
		(pin "R9"
		)
		(pin "T12"
		)
		(pin "R12"
		)
		(pin "R13"
		)
		(pin "R14"
		)
		(pin "R15"
		)
		(pin "AB11"
		)
		(pin "AB12"
		)
		(pin "AB13"
		)
		(pin "AB5"
		)
		(pin "AB6"
		)
		(pin "T17"
		)
		(pin "T2"
		)
		(pin "T22"
		)
		(pin "T7"
		)
		(pin "U14"
		)
		(pin "U19"
		)
		(pin "R10"
		)
		(pin "R11"
		)
		(pin "U4"
		)
		(pin "U9"
		)
		(pin "V1"
		)
		(pin "V11"
		)
		(pin "V16"
		)
		(pin "V21"
		)
		(pin "V6"
		)
		(pin "W13"
		)
		(pin "W18"
		)
		(pin "W3"
		)
		(pin "W8"
		)
		(pin "Y10"
		)
		(pin "Y15"
		)
		(pin "Y20"
		)
		(pin "Y5"
		)
		(pin "G7"
		)
		(pin "H6"
		)
		(pin "H7"
		)
		(pin "J5"
		)
		(pin "J6"
		)
		(pin "K6"
		)
		(pin "K7"
		)
		(pin "L11"
		)
		(pin "L12"
		)
		(pin "L6"
		)
		(pin "L7"
		)
		(pin "M11"
		)
		(pin "M12"
		)
		(pin "M6"
		)
		(pin "A1"
		)
		(pin "A12"
		)
		(pin "A17"
		)
		(pin "A2"
		)
		(pin "A22"
		)
		(pin "A5"
		)
		(pin "A6"
		)
		(pin "A7"
		)
		(pin "AA12"
		)
		(pin "AA17"
		)
		(pin "AA2"
		)
		(pin "AA22"
		)
		(pin "AA7"
		)
		(pin "AB14"
		)
		(pin "AB19"
		)
		(pin "AB4"
		)
		(pin "AB9"
		)
		(pin "B14"
		)
		(pin "B19"
		)
		(pin "B3"
		)
		(pin "B4"
		)
		(pin "B7"
		)
		(pin "B9"
		)
		(pin "C1"
		)
		(pin "C11"
		)
		(pin "C16"
		)
		(pin "C2"
		)
		(pin "C21"
		)
		(pin "C5"
		)
		(pin "C6"
		)
		(pin "C7"
		)
		(pin "D13"
		)
		(pin "D18"
		)
		(pin "D3"
		)
		(pin "D4"
		)
		(pin "D7"
		)
		(pin "D8"
		)
		(pin "E1"
		)
		(pin "E10"
		)
		(pin "E15"
		)
		(pin "E2"
		)
		(pin "E20"
		)
		(pin "E5"
		)
		(pin "E6"
		)
		(pin "E7"
		)
		(pin "F12"
		)
		(pin "F17"
		)
		(pin "F22"
		)
		(pin "F3"
		)
		(pin "F4"
		)
		(pin "F7"
		)
		(pin "G1"
		)
		(pin "G14"
		)
		(pin "G19"
		)
		(pin "G2"
		)
		(pin "G5"
		)
		(pin "G6"
		)
		(pin "G9"
		)
		(pin "H1"
		)
		(pin "H11"
		)
		(pin "H16"
		)
		(pin "H2"
		)
		(pin "H21"
		)
		(pin "H3"
		)
		(pin "H4"
		)
		(pin "H5"
		)
		(pin "J1"
		)
		(pin "J10"
		)
		(pin "J11"
		)
		(pin "J12"
		)
		(pin "J13"
		)
		(pin "J14"
		)
		(pin "J15"
		)
		(pin "J18"
		)
		(pin "J2"
		)
		(pin "J3"
		)
		(pin "J4"
		)
		(pin "J7"
		)
		(pin "J8"
		)
		(pin "J9"
		)
		(pin "K10"
		)
		(pin "K11"
		)
		(pin "K12"
		)
		(pin "K13"
		)
		(pin "K14"
		)
		(pin "K15"
		)
		(pin "K20"
		)
		(pin "K5"
		)
		(pin "K8"
		)
		(pin "K9"
		)
		(pin "L10"
		)
		(pin "L13"
		)
		(pin "L14"
		)
		(pin "L15"
		)
		(pin "L17"
		)
		(pin "L2"
		)
		(pin "L22"
		)
		(pin "L8"
		)
		(pin "L9"
		)
		(pin "M10"
		)
		(pin "M13"
		)
		(pin "M14"
		)
		(pin "M15"
		)
		(pin "M19"
		)
		(pin "M4"
		)
		(pin "M8"
		)
		(pin "M9"
		)
		(pin "N1"
		)
		(pin "N10"
		)
		(pin "N13"
		)
		(pin "N14"
		)
		(pin "N15"
		)
		(pin "N16"
		)
		(pin "N21"
		)
		(pin "N6"
		)
		(pin "N7"
		)
		(pin "N8"
		)
		(pin "N9"
		)
		(pin "P10"
		)
		(pin "P11"
		)
		(pin "P12"
		)
		(pin "P13"
		)
		(pin "P14"
		)
		(pin "P15"
		)
		(pin "P18"
		)
		(pin "P3"
		)
		(pin "P7"
		)
		(pin "P8"
		)
		(pin "P9"
		)
		(pin "M7"
		)
		(pin "N11"
		)
		(pin "N12"
		)
		(pin "P6"
		)
		(pin "A3"
		)
		(pin "A4"
		)
		(pin "B1"
		)
		(pin "B2"
		)
		(pin "B5"
		)
		(pin "B6"
		)
		(pin "C3"
		)
		(pin "C4"
		)
		(pin "D1"
		)
		(pin "D2"
		)
		(pin "D5"
		)
		(pin "D6"
		)
		(pin "E3"
		)
		(pin "E4"
		)
		(pin "F1"
		)
		(pin "F2"
		)
		(pin "F5"
		)
		(pin "F6"
		)
		(pin "G3"
		)
		(pin "G4"
		)
		(pin "AA10"
		)
		(pin "AA11"
		)
		(pin "AA13"
		)
		(pin "AA5"
		)
		(pin "AA6"
		)
		(pin "AA8"
		)
		(pin "AA9"
		)
		(pin "AB10"
		)
		(pin "AB7"
		)
		(pin "AB8"
		)
		(pin "R6"
		)
		(pin "R7"
		)
		(pin "T10"
		)
		(pin "T11"
		)
		(pin "T13"
		)
		(pin "T14"
		)
		(pin "T6"
		)
		(pin "T8"
		)
		(pin "T9"
		)
		(pin "U10"
		)
		(pin "U11"
		)
		(pin "U12"
		)
		(pin "U13"
		)
		(pin "U6"
		)
		(pin "U7"
		)
		(pin "U8"
		)
		(pin "V10"
		)
		(pin "V12"
		)
		(pin "V13"
		)
		(pin "V7"
		)
		(pin "V8"
		)
		(pin "V9"
		)
		(pin "W10"
		)
		(pin "W11"
		)
		(pin "W12"
		)
		(pin "W6"
		)
		(pin "W7"
		)
		(pin "W9"
		)
		(pin "Y11"
		)
		(pin "Y12"
		)
		(pin "Y13"
		)
		(pin "Y6"
		)
		(pin "Y7"
		)
		(pin "Y8"
		)
		(pin "Y9"
		)
		(pin "A10"
		)
		(pin "A11"
		)
		(pin "A8"
		)
		(pin "A9"
		)
		(pin "B10"
		)
		(pin "B11"
		)
		(pin "B8"
		)
		(pin "C10"
		)
		(pin "C8"
		)
		(pin "C9"
		)
		(pin "D10"
		)
		(pin "D11"
		)
		(pin "D9"
		)
		(pin "E11"
		)
		(pin "E12"
		)
		(pin "E13"
		)
		(pin "E8"
		)
		(pin "E9"
		)
		(pin "F10"
		)
		(pin "F11"
		)
		(pin "F13"
		)
		(pin "F14"
		)
		(pin "F8"
		)
		(pin "F9"
		)
		(pin "G10"
		)
		(pin "G11"
		)
		(pin "G12"
		)
		(pin "G13"
		)
		(pin "G8"
		)
		(pin "H10"
		)
		(pin "H12"
		)
		(pin "H13"
		)
		(pin "H14"
		)
		(pin "H8"
		)
		(pin "H9"
		)
		(pin "A13"
		)
		(pin "A14"
		)
		(pin "A15"
		)
		(pin "A16"
		)
		(pin "A18"
		)
		(pin "A19"
		)
		(pin "A20"
		)
		(pin "A21"
		)
		(pin "B12"
		)
		(pin "B13"
		)
		(pin "B15"
		)
		(pin "B16"
		)
		(pin "B17"
		)
		(pin "B18"
		)
		(pin "B20"
		)
		(pin "B21"
		)
		(pin "B22"
		)
		(pin "C12"
		)
		(pin "C13"
		)
		(pin "C14"
		)
		(pin "C15"
		)
		(pin "C17"
		)
		(pin "C18"
		)
		(pin "C19"
		)
		(pin "C20"
		)
		(pin "C22"
		)
		(pin "D12"
		)
		(pin "D14"
		)
		(pin "D15"
		)
		(pin "D16"
		)
		(pin "D17"
		)
		(pin "D19"
		)
		(pin "D20"
		)
		(pin "D21"
		)
		(pin "D22"
		)
		(pin "E14"
		)
		(pin "E16"
		)
		(pin "E17"
		)
		(pin "E18"
		)
		(pin "E19"
		)
		(pin "F15"
		)
		(pin "F16"
		)
		(pin "F18"
		)
		(pin "G15"
		)
		(pin "G16"
		)
		(pin "G17"
		)
		(pin "H15"
		)
		(pin "H17"
		)
		(pin "J16"
		)
		(pin "J17"
		)
		(pin "E21"
		)
		(pin "E22"
		)
		(pin "F19"
		)
		(pin "F20"
		)
		(pin "F21"
		)
		(pin "G18"
		)
		(pin "G20"
		)
		(pin "G21"
		)
		(pin "G22"
		)
		(pin "H18"
		)
		(pin "H19"
		)
		(pin "H20"
		)
		(pin "H22"
		)
		(pin "J19"
		)
		(pin "J20"
		)
		(pin "J21"
		)
		(pin "J22"
		)
		(pin "K16"
		)
		(pin "K17"
		)
		(pin "K18"
		)
		(pin "K19"
		)
		(pin "K21"
		)
		(pin "K22"
		)
		(pin "L16"
		)
		(pin "L18"
		)
		(pin "L19"
		)
		(pin "L20"
		)
		(pin "L21"
		)
		(pin "M16"
		)
		(pin "M17"
		)
		(pin "M18"
		)
		(pin "M20"
		)
		(pin "M21"
		)
		(pin "M22"
		)
		(pin "N17"
		)
		(pin "N18"
		)
		(pin "N19"
		)
		(pin "N20"
		)
		(pin "N22"
		)
		(pin "P16"
		)
		(pin "P17"
		)
		(pin "P19"
		)
		(pin "P20"
		)
		(pin "P21"
		)
		(pin "P22"
		)
		(pin "R17"
		)
		(pin "R18"
		)
		(pin "R19"
		)
		(pin "R21"
		)
		(pin "R22"
		)
		(pin "AA14"
		)
		(pin "AA15"
		)
		(pin "AA16"
		)
		(pin "AA18"
		)
		(pin "AA19"
		)
		(pin "AA20"
		)
		(pin "AA21"
		)
		(pin "AB15"
		)
		(pin "AB16"
		)
		(pin "AB17"
		)
		(pin "AB18"
		)
		(pin "AB20"
		)
		(pin "AB21"
		)
		(pin "AB22"
		)
		(pin "R16"
		)
		(pin "T15"
		)
		(pin "T16"
		)
		(pin "T18"
		)
		(pin "T19"
		)
		(pin "T20"
		)
		(pin "T21"
		)
		(pin "U15"
		)
		(pin "U16"
		)
		(pin "U17"
		)
		(pin "U18"
		)
		(pin "U20"
		)
		(pin "U21"
		)
		(pin "U22"
		)
		(pin "V14"
		)
		(pin "V15"
		)
		(pin "V17"
		)
		(pin "V18"
		)
		(pin "V19"
		)
		(pin "V20"
		)
		(pin "V22"
		)
		(pin "W14"
		)
		(pin "W15"
		)
		(pin "W16"
		)
		(pin "W17"
		)
		(pin "W19"
		)
		(pin "W20"
		)
		(pin "W21"
		)
		(pin "W22"
		)
		(pin "Y14"
		)
		(pin "Y16"
		)
		(pin "Y17"
		)
		(pin "Y18"
		)
		(pin "Y19"
		)
		(pin "Y21"
		)
		(pin "Y22"
		)
		(instances
			(project "lpddr4-test-board"
				(path ""
					(reference "U3")
					(unit 4)
				)
			)
		)
	)
	(symbol
		(lib_id "antmicroFPGAChips:XC7K70T-FBG484")
		(at 252.73 41.275 0)
		(mirror y)
		(unit 6)
		(exclude_from_sim no)
		(in_bom yes)
		(on_board yes)
		(dnp no)
		(property "Reference" "U3"
			(at 247.65 33.02 0)
			(effects
				(font
					(size 1.27 1.27)
					(thickness 0.15)
				)
				(justify left bottom)
			)
		)
		(property "Value" "XC7K70T-FBG484"
			(at 199.39 46.355 0)
			(effects
				(font
					(size 1.27 1.27)
					(thickness 0.15)
				)
				(justify left bottom)
				(hide yes)
			)
		)
		(property "Footprint" "antmicro-footprints:BGA-484_23x23mm_Layout22x22_P1mm_FBG484"
			(at 199.39 48.895 0)
			(effects
				(font
					(size 1.27 1.27)
					(thickness 0.15)
				)
				(justify left bottom)
				(hide yes)
			)
		)
		(property "Datasheet" "https://docs.xilinx.com/v/u/en-US/ds182_Kintex_7_Data_Sheet"
			(at 199.39 51.435 0)
			(effects
				(font
					(size 1.27 1.27)
					(thickness 0.15)
				)
				(justify left bottom)
				(hide yes)
			)
		)
		(property "Description" ""
			(at 252.73 41.275 0)
			(effects
				(font
					(size 1.27 1.27)
				)
			)
		)
		(property "Manufacturer" "AMD-Xilinx"
			(at 199.39 53.975 0)
			(effects
				(font
					(size 1.27 1.27)
					(thickness 0.15)
				)
				(justify left bottom)
				(hide yes)
			)
		)
		(property "MPN" "XC7K70T-1FBG484C"
			(at 198.12 35.56 0)
			(effects
				(font
					(size 1.27 1.27)
					(thickness 0.15)
				)
				(justify left bottom)
			)
		)
		(property "Author" "Antmicro"
			(at 199.39 56.515 0)
			(effects
				(font
					(size 1.27 1.27)
					(thickness 0.15)
				)
				(justify left bottom)
				(hide yes)
			)
		)
		(property "License" "Apache-2.0"
			(at 199.39 59.055 0)
			(effects
				(font
					(size 1.27 1.27)
					(thickness 0.15)
				)
				(justify left bottom)
				(hide yes)
			)
		)
		(pin "A10"
		)
		(pin "A11"
		)
		(pin "A8"
		)
		(pin "A9"
		)
		(pin "B10"
		)
		(pin "B11"
		)
		(pin "B8"
		)
		(pin "C10"
		)
		(pin "C8"
		)
		(pin "C9"
		)
		(pin "D10"
		)
		(pin "D11"
		)
		(pin "D9"
		)
		(pin "E11"
		)
		(pin "E12"
		)
		(pin "E13"
		)
		(pin "E8"
		)
		(pin "E9"
		)
		(pin "F10"
		)
		(pin "F11"
		)
		(pin "F13"
		)
		(pin "F14"
		)
		(pin "F8"
		)
		(pin "F9"
		)
		(pin "G10"
		)
		(pin "G11"
		)
		(pin "G12"
		)
		(pin "G13"
		)
		(pin "G8"
		)
		(pin "H10"
		)
		(pin "H12"
		)
		(pin "H13"
		)
		(pin "H14"
		)
		(pin "H8"
		)
		(pin "H9"
		)
		(pin "A1"
		)
		(pin "A12"
		)
		(pin "A17"
		)
		(pin "A2"
		)
		(pin "A22"
		)
		(pin "A5"
		)
		(pin "A6"
		)
		(pin "A7"
		)
		(pin "AA12"
		)
		(pin "AA17"
		)
		(pin "AA2"
		)
		(pin "AA22"
		)
		(pin "AA7"
		)
		(pin "AB14"
		)
		(pin "AB19"
		)
		(pin "AB4"
		)
		(pin "AB9"
		)
		(pin "B14"
		)
		(pin "B19"
		)
		(pin "B3"
		)
		(pin "B4"
		)
		(pin "B7"
		)
		(pin "B9"
		)
		(pin "C1"
		)
		(pin "C11"
		)
		(pin "C16"
		)
		(pin "C2"
		)
		(pin "C21"
		)
		(pin "C5"
		)
		(pin "C6"
		)
		(pin "C7"
		)
		(pin "D13"
		)
		(pin "D18"
		)
		(pin "D3"
		)
		(pin "D4"
		)
		(pin "D7"
		)
		(pin "D8"
		)
		(pin "E1"
		)
		(pin "E10"
		)
		(pin "E15"
		)
		(pin "E2"
		)
		(pin "E20"
		)
		(pin "E5"
		)
		(pin "E6"
		)
		(pin "E7"
		)
		(pin "F12"
		)
		(pin "F17"
		)
		(pin "F22"
		)
		(pin "F3"
		)
		(pin "F4"
		)
		(pin "F7"
		)
		(pin "G1"
		)
		(pin "G14"
		)
		(pin "G19"
		)
		(pin "G2"
		)
		(pin "G5"
		)
		(pin "G6"
		)
		(pin "G9"
		)
		(pin "H1"
		)
		(pin "H11"
		)
		(pin "H16"
		)
		(pin "H2"
		)
		(pin "H21"
		)
		(pin "H3"
		)
		(pin "H4"
		)
		(pin "H5"
		)
		(pin "J1"
		)
		(pin "J10"
		)
		(pin "J11"
		)
		(pin "J12"
		)
		(pin "J13"
		)
		(pin "J14"
		)
		(pin "J15"
		)
		(pin "J18"
		)
		(pin "J2"
		)
		(pin "J3"
		)
		(pin "J4"
		)
		(pin "J7"
		)
		(pin "J8"
		)
		(pin "J9"
		)
		(pin "K10"
		)
		(pin "K11"
		)
		(pin "K12"
		)
		(pin "K13"
		)
		(pin "K14"
		)
		(pin "K15"
		)
		(pin "K20"
		)
		(pin "K5"
		)
		(pin "K8"
		)
		(pin "K9"
		)
		(pin "L10"
		)
		(pin "L13"
		)
		(pin "L14"
		)
		(pin "L15"
		)
		(pin "L17"
		)
		(pin "L2"
		)
		(pin "L22"
		)
		(pin "L8"
		)
		(pin "L9"
		)
		(pin "M10"
		)
		(pin "M13"
		)
		(pin "M14"
		)
		(pin "M15"
		)
		(pin "M19"
		)
		(pin "M4"
		)
		(pin "M8"
		)
		(pin "M9"
		)
		(pin "N1"
		)
		(pin "N10"
		)
		(pin "N13"
		)
		(pin "N14"
		)
		(pin "N15"
		)
		(pin "N16"
		)
		(pin "N21"
		)
		(pin "N6"
		)
		(pin "N7"
		)
		(pin "N8"
		)
		(pin "N9"
		)
		(pin "P10"
		)
		(pin "P11"
		)
		(pin "P12"
		)
		(pin "P13"
		)
		(pin "P14"
		)
		(pin "P15"
		)
		(pin "P18"
		)
		(pin "P3"
		)
		(pin "P7"
		)
		(pin "P8"
		)
		(pin "P9"
		)
		(pin "AB11"
		)
		(pin "AB12"
		)
		(pin "AB13"
		)
		(pin "AB5"
		)
		(pin "AB6"
		)
		(pin "R10"
		)
		(pin "R11"
		)
		(pin "R12"
		)
		(pin "R13"
		)
		(pin "R14"
		)
		(pin "R15"
		)
		(pin "R20"
		)
		(pin "R5"
		)
		(pin "R8"
		)
		(pin "R9"
		)
		(pin "T12"
		)
		(pin "T17"
		)
		(pin "T2"
		)
		(pin "T22"
		)
		(pin "T7"
		)
		(pin "U14"
		)
		(pin "U19"
		)
		(pin "U4"
		)
		(pin "U9"
		)
		(pin "V1"
		)
		(pin "V11"
		)
		(pin "V16"
		)
		(pin "V21"
		)
		(pin "V6"
		)
		(pin "W13"
		)
		(pin "W18"
		)
		(pin "W3"
		)
		(pin "W8"
		)
		(pin "Y10"
		)
		(pin "Y15"
		)
		(pin "Y20"
		)
		(pin "Y5"
		)
		(pin "G7"
		)
		(pin "H6"
		)
		(pin "H7"
		)
		(pin "J5"
		)
		(pin "J6"
		)
		(pin "K6"
		)
		(pin "K7"
		)
		(pin "L11"
		)
		(pin "L12"
		)
		(pin "L6"
		)
		(pin "L7"
		)
		(pin "M11"
		)
		(pin "M12"
		)
		(pin "M6"
		)
		(pin "M7"
		)
		(pin "N11"
		)
		(pin "N12"
		)
		(pin "P6"
		)
		(pin "A3"
		)
		(pin "A4"
		)
		(pin "B1"
		)
		(pin "B2"
		)
		(pin "B5"
		)
		(pin "B6"
		)
		(pin "C3"
		)
		(pin "C4"
		)
		(pin "D1"
		)
		(pin "D2"
		)
		(pin "D5"
		)
		(pin "D6"
		)
		(pin "E3"
		)
		(pin "E4"
		)
		(pin "F1"
		)
		(pin "F2"
		)
		(pin "F5"
		)
		(pin "F6"
		)
		(pin "G3"
		)
		(pin "G4"
		)
		(pin "AA1"
		)
		(pin "AA3"
		)
		(pin "AA4"
		)
		(pin "AB1"
		)
		(pin "AB2"
		)
		(pin "AB3"
		)
		(pin "K1"
		)
		(pin "K2"
		)
		(pin "K3"
		)
		(pin "K4"
		)
		(pin "L1"
		)
		(pin "L3"
		)
		(pin "L4"
		)
		(pin "L5"
		)
		(pin "M1"
		)
		(pin "M2"
		)
		(pin "M3"
		)
		(pin "M5"
		)
		(pin "N2"
		)
		(pin "N3"
		)
		(pin "N4"
		)
		(pin "N5"
		)
		(pin "P1"
		)
		(pin "P2"
		)
		(pin "P4"
		)
		(pin "P5"
		)
		(pin "R1"
		)
		(pin "R2"
		)
		(pin "R3"
		)
		(pin "R4"
		)
		(pin "T1"
		)
		(pin "T3"
		)
		(pin "T4"
		)
		(pin "T5"
		)
		(pin "U1"
		)
		(pin "U2"
		)
		(pin "U3"
		)
		(pin "U5"
		)
		(pin "V2"
		)
		(pin "V3"
		)
		(pin "V4"
		)
		(pin "V5"
		)
		(pin "W1"
		)
		(pin "W2"
		)
		(pin "W4"
		)
		(pin "W5"
		)
		(pin "Y1"
		)
		(pin "Y2"
		)
		(pin "Y3"
		)
		(pin "Y4"
		)
		(pin "AA10"
		)
		(pin "AA11"
		)
		(pin "AA13"
		)
		(pin "AA5"
		)
		(pin "AA6"
		)
		(pin "AA8"
		)
		(pin "AA9"
		)
		(pin "AB10"
		)
		(pin "AB7"
		)
		(pin "AB8"
		)
		(pin "R6"
		)
		(pin "R7"
		)
		(pin "T10"
		)
		(pin "T11"
		)
		(pin "T13"
		)
		(pin "T14"
		)
		(pin "T6"
		)
		(pin "T8"
		)
		(pin "T9"
		)
		(pin "U10"
		)
		(pin "U11"
		)
		(pin "U12"
		)
		(pin "U13"
		)
		(pin "U6"
		)
		(pin "U7"
		)
		(pin "U8"
		)
		(pin "V10"
		)
		(pin "V12"
		)
		(pin "V13"
		)
		(pin "V7"
		)
		(pin "V8"
		)
		(pin "V9"
		)
		(pin "W10"
		)
		(pin "W11"
		)
		(pin "W12"
		)
		(pin "W6"
		)
		(pin "W7"
		)
		(pin "W9"
		)
		(pin "Y11"
		)
		(pin "Y12"
		)
		(pin "Y13"
		)
		(pin "Y6"
		)
		(pin "Y7"
		)
		(pin "Y8"
		)
		(pin "Y9"
		)
		(pin "A13"
		)
		(pin "A14"
		)
		(pin "A15"
		)
		(pin "A16"
		)
		(pin "A18"
		)
		(pin "A19"
		)
		(pin "A20"
		)
		(pin "A21"
		)
		(pin "B12"
		)
		(pin "B13"
		)
		(pin "B15"
		)
		(pin "B16"
		)
		(pin "B17"
		)
		(pin "B18"
		)
		(pin "B20"
		)
		(pin "B21"
		)
		(pin "B22"
		)
		(pin "C12"
		)
		(pin "C13"
		)
		(pin "C14"
		)
		(pin "C15"
		)
		(pin "C17"
		)
		(pin "C18"
		)
		(pin "C19"
		)
		(pin "C20"
		)
		(pin "C22"
		)
		(pin "D12"
		)
		(pin "D14"
		)
		(pin "D15"
		)
		(pin "D16"
		)
		(pin "D17"
		)
		(pin "D19"
		)
		(pin "D20"
		)
		(pin "D21"
		)
		(pin "D22"
		)
		(pin "E14"
		)
		(pin "E16"
		)
		(pin "E17"
		)
		(pin "E18"
		)
		(pin "E19"
		)
		(pin "F15"
		)
		(pin "F16"
		)
		(pin "F18"
		)
		(pin "G15"
		)
		(pin "G16"
		)
		(pin "G17"
		)
		(pin "H15"
		)
		(pin "H17"
		)
		(pin "J16"
		)
		(pin "J17"
		)
		(pin "E21"
		)
		(pin "E22"
		)
		(pin "F19"
		)
		(pin "F20"
		)
		(pin "F21"
		)
		(pin "G18"
		)
		(pin "G20"
		)
		(pin "G21"
		)
		(pin "G22"
		)
		(pin "H18"
		)
		(pin "H19"
		)
		(pin "H20"
		)
		(pin "H22"
		)
		(pin "J19"
		)
		(pin "J20"
		)
		(pin "J21"
		)
		(pin "J22"
		)
		(pin "K16"
		)
		(pin "K17"
		)
		(pin "K18"
		)
		(pin "K19"
		)
		(pin "K21"
		)
		(pin "K22"
		)
		(pin "L16"
		)
		(pin "L18"
		)
		(pin "L19"
		)
		(pin "L20"
		)
		(pin "L21"
		)
		(pin "M16"
		)
		(pin "M17"
		)
		(pin "M18"
		)
		(pin "M20"
		)
		(pin "M21"
		)
		(pin "M22"
		)
		(pin "N17"
		)
		(pin "N18"
		)
		(pin "N19"
		)
		(pin "N20"
		)
		(pin "N22"
		)
		(pin "P16"
		)
		(pin "P17"
		)
		(pin "P19"
		)
		(pin "P20"
		)
		(pin "P21"
		)
		(pin "P22"
		)
		(pin "R17"
		)
		(pin "R18"
		)
		(pin "R19"
		)
		(pin "R21"
		)
		(pin "R22"
		)
		(pin "AA14"
		)
		(pin "AA15"
		)
		(pin "AA16"
		)
		(pin "AA18"
		)
		(pin "AA19"
		)
		(pin "AA20"
		)
		(pin "AA21"
		)
		(pin "AB15"
		)
		(pin "AB16"
		)
		(pin "AB17"
		)
		(pin "AB18"
		)
		(pin "AB20"
		)
		(pin "AB21"
		)
		(pin "AB22"
		)
		(pin "R16"
		)
		(pin "T15"
		)
		(pin "T16"
		)
		(pin "T18"
		)
		(pin "T19"
		)
		(pin "T20"
		)
		(pin "T21"
		)
		(pin "U15"
		)
		(pin "U16"
		)
		(pin "U17"
		)
		(pin "U18"
		)
		(pin "U20"
		)
		(pin "U21"
		)
		(pin "U22"
		)
		(pin "V14"
		)
		(pin "V15"
		)
		(pin "V17"
		)
		(pin "V18"
		)
		(pin "V19"
		)
		(pin "V20"
		)
		(pin "V22"
		)
		(pin "W14"
		)
		(pin "W15"
		)
		(pin "W16"
		)
		(pin "W17"
		)
		(pin "W19"
		)
		(pin "W20"
		)
		(pin "W21"
		)
		(pin "W22"
		)
		(pin "Y14"
		)
		(pin "Y16"
		)
		(pin "Y17"
		)
		(pin "Y18"
		)
		(pin "Y19"
		)
		(pin "Y21"
		)
		(pin "Y22"
		)
		(instances
			(project "lpddr4-test-board"
				(path ""
					(reference "U3")
					(unit 6)
				)
			)
		)
	)
	(symbol
		(lib_id "antmicroFPGAChips:XC7K70T-FBG484")
		(at 37.465 41.275 0)
		(unit 9)
		(exclude_from_sim no)
		(in_bom yes)
		(on_board yes)
		(dnp no)
		(property "Reference" "U3"
			(at 42.545 33.02 0)
			(effects
				(font
					(size 1.27 1.27)
					(thickness 0.15)
				)
				(justify left bottom)
			)
		)
		(property "Value" "XC7K70T-FBG484"
			(at 90.805 46.355 0)
			(effects
				(font
					(size 1.27 1.27)
					(thickness 0.15)
				)
				(justify left bottom)
				(hide yes)
			)
		)
		(property "Footprint" "antmicro-footprints:BGA-484_23x23mm_Layout22x22_P1mm_FBG484"
			(at 90.805 48.895 0)
			(effects
				(font
					(size 1.27 1.27)
					(thickness 0.15)
				)
				(justify left bottom)
				(hide yes)
			)
		)
		(property "Datasheet" "https://docs.xilinx.com/v/u/en-US/ds182_Kintex_7_Data_Sheet"
			(at 90.805 51.435 0)
			(effects
				(font
					(size 1.27 1.27)
					(thickness 0.15)
				)
				(justify left bottom)
				(hide yes)
			)
		)
		(property "Description" ""
			(at 37.465 41.275 0)
			(effects
				(font
					(size 1.27 1.27)
				)
			)
		)
		(property "Manufacturer" "AMD-Xilinx"
			(at 90.805 53.975 0)
			(effects
				(font
					(size 1.27 1.27)
					(thickness 0.15)
				)
				(justify left bottom)
				(hide yes)
			)
		)
		(property "MPN" "XC7K70T-1FBG484C"
			(at 92.71 35.56 0)
			(effects
				(font
					(size 1.27 1.27)
					(thickness 0.15)
				)
				(justify left bottom)
			)
		)
		(property "Author" "Antmicro"
			(at 90.805 56.515 0)
			(effects
				(font
					(size 1.27 1.27)
					(thickness 0.15)
				)
				(justify left bottom)
				(hide yes)
			)
		)
		(property "License" "Apache-2.0"
			(at 90.805 59.055 0)
			(effects
				(font
					(size 1.27 1.27)
					(thickness 0.15)
				)
				(justify left bottom)
				(hide yes)
			)
		)
		(pin "AA14"
		)
		(pin "AA15"
		)
		(pin "AA16"
		)
		(pin "AA18"
		)
		(pin "AA19"
		)
		(pin "AA20"
		)
		(pin "AA21"
		)
		(pin "AB15"
		)
		(pin "AB16"
		)
		(pin "AB17"
		)
		(pin "AB18"
		)
		(pin "AB20"
		)
		(pin "AB21"
		)
		(pin "AB22"
		)
		(pin "R16"
		)
		(pin "T15"
		)
		(pin "T16"
		)
		(pin "T18"
		)
		(pin "T19"
		)
		(pin "T20"
		)
		(pin "T21"
		)
		(pin "U15"
		)
		(pin "U16"
		)
		(pin "U17"
		)
		(pin "U18"
		)
		(pin "U20"
		)
		(pin "U21"
		)
		(pin "U22"
		)
		(pin "V14"
		)
		(pin "V15"
		)
		(pin "V17"
		)
		(pin "V18"
		)
		(pin "V19"
		)
		(pin "V20"
		)
		(pin "V22"
		)
		(pin "W14"
		)
		(pin "W15"
		)
		(pin "W16"
		)
		(pin "W17"
		)
		(pin "W19"
		)
		(pin "W20"
		)
		(pin "W21"
		)
		(pin "W22"
		)
		(pin "Y14"
		)
		(pin "Y16"
		)
		(pin "Y17"
		)
		(pin "Y18"
		)
		(pin "Y19"
		)
		(pin "Y21"
		)
		(pin "Y22"
		)
		(pin "A17"
		)
		(pin "A1"
		)
		(pin "A5"
		)
		(pin "A6"
		)
		(pin "A2"
		)
		(pin "A22"
		)
		(pin "A12"
		)
		(pin "A7"
		)
		(pin "AA12"
		)
		(pin "AA17"
		)
		(pin "AA2"
		)
		(pin "AA22"
		)
		(pin "AA7"
		)
		(pin "AB14"
		)
		(pin "AB19"
		)
		(pin "AB4"
		)
		(pin "AB9"
		)
		(pin "B14"
		)
		(pin "B19"
		)
		(pin "B3"
		)
		(pin "B4"
		)
		(pin "B7"
		)
		(pin "B9"
		)
		(pin "C1"
		)
		(pin "C11"
		)
		(pin "C16"
		)
		(pin "C2"
		)
		(pin "C21"
		)
		(pin "C5"
		)
		(pin "C6"
		)
		(pin "C7"
		)
		(pin "D13"
		)
		(pin "D18"
		)
		(pin "D3"
		)
		(pin "D4"
		)
		(pin "D7"
		)
		(pin "D8"
		)
		(pin "E1"
		)
		(pin "E10"
		)
		(pin "E15"
		)
		(pin "E2"
		)
		(pin "E20"
		)
		(pin "E5"
		)
		(pin "E6"
		)
		(pin "E7"
		)
		(pin "F12"
		)
		(pin "F17"
		)
		(pin "F22"
		)
		(pin "F3"
		)
		(pin "F4"
		)
		(pin "F7"
		)
		(pin "G1"
		)
		(pin "G14"
		)
		(pin "G19"
		)
		(pin "G2"
		)
		(pin "G5"
		)
		(pin "G6"
		)
		(pin "G9"
		)
		(pin "H1"
		)
		(pin "H11"
		)
		(pin "H16"
		)
		(pin "H2"
		)
		(pin "H21"
		)
		(pin "H3"
		)
		(pin "H4"
		)
		(pin "H5"
		)
		(pin "J1"
		)
		(pin "J10"
		)
		(pin "J11"
		)
		(pin "J12"
		)
		(pin "J13"
		)
		(pin "J14"
		)
		(pin "J15"
		)
		(pin "J18"
		)
		(pin "J2"
		)
		(pin "J3"
		)
		(pin "J4"
		)
		(pin "J7"
		)
		(pin "J8"
		)
		(pin "J9"
		)
		(pin "K10"
		)
		(pin "K11"
		)
		(pin "K12"
		)
		(pin "K13"
		)
		(pin "K14"
		)
		(pin "K15"
		)
		(pin "K20"
		)
		(pin "K5"
		)
		(pin "K8"
		)
		(pin "K9"
		)
		(pin "L10"
		)
		(pin "L13"
		)
		(pin "L14"
		)
		(pin "L15"
		)
		(pin "L17"
		)
		(pin "L2"
		)
		(pin "L22"
		)
		(pin "L8"
		)
		(pin "L9"
		)
		(pin "M10"
		)
		(pin "M13"
		)
		(pin "M14"
		)
		(pin "M15"
		)
		(pin "M19"
		)
		(pin "M4"
		)
		(pin "M8"
		)
		(pin "M9"
		)
		(pin "N1"
		)
		(pin "N10"
		)
		(pin "N13"
		)
		(pin "N14"
		)
		(pin "N15"
		)
		(pin "N16"
		)
		(pin "N21"
		)
		(pin "N6"
		)
		(pin "N7"
		)
		(pin "N8"
		)
		(pin "N9"
		)
		(pin "P10"
		)
		(pin "P11"
		)
		(pin "P12"
		)
		(pin "P13"
		)
		(pin "P14"
		)
		(pin "P15"
		)
		(pin "P18"
		)
		(pin "P3"
		)
		(pin "P7"
		)
		(pin "P8"
		)
		(pin "P9"
		)
		(pin "AB11"
		)
		(pin "AB12"
		)
		(pin "AB13"
		)
		(pin "AB5"
		)
		(pin "AB6"
		)
		(pin "R10"
		)
		(pin "R11"
		)
		(pin "R12"
		)
		(pin "R13"
		)
		(pin "R14"
		)
		(pin "R15"
		)
		(pin "R20"
		)
		(pin "R5"
		)
		(pin "R8"
		)
		(pin "R9"
		)
		(pin "T12"
		)
		(pin "T17"
		)
		(pin "T2"
		)
		(pin "T22"
		)
		(pin "T7"
		)
		(pin "U14"
		)
		(pin "U19"
		)
		(pin "U4"
		)
		(pin "U9"
		)
		(pin "V1"
		)
		(pin "V11"
		)
		(pin "V16"
		)
		(pin "V21"
		)
		(pin "V6"
		)
		(pin "W13"
		)
		(pin "W18"
		)
		(pin "W3"
		)
		(pin "W8"
		)
		(pin "Y10"
		)
		(pin "Y15"
		)
		(pin "Y20"
		)
		(pin "Y5"
		)
		(pin "G7"
		)
		(pin "H6"
		)
		(pin "H7"
		)
		(pin "J5"
		)
		(pin "J6"
		)
		(pin "K6"
		)
		(pin "K7"
		)
		(pin "L11"
		)
		(pin "L12"
		)
		(pin "L6"
		)
		(pin "L7"
		)
		(pin "M11"
		)
		(pin "M12"
		)
		(pin "M6"
		)
		(pin "M7"
		)
		(pin "N11"
		)
		(pin "N12"
		)
		(pin "P6"
		)
		(pin "A3"
		)
		(pin "A4"
		)
		(pin "B1"
		)
		(pin "B2"
		)
		(pin "B5"
		)
		(pin "B6"
		)
		(pin "C3"
		)
		(pin "C4"
		)
		(pin "D1"
		)
		(pin "D2"
		)
		(pin "D5"
		)
		(pin "D6"
		)
		(pin "E3"
		)
		(pin "E4"
		)
		(pin "F1"
		)
		(pin "F2"
		)
		(pin "F5"
		)
		(pin "F6"
		)
		(pin "G3"
		)
		(pin "G4"
		)
		(pin "AA1"
		)
		(pin "AA3"
		)
		(pin "AA4"
		)
		(pin "AB1"
		)
		(pin "AB2"
		)
		(pin "AB3"
		)
		(pin "K1"
		)
		(pin "K2"
		)
		(pin "K3"
		)
		(pin "K4"
		)
		(pin "L1"
		)
		(pin "L3"
		)
		(pin "L4"
		)
		(pin "L5"
		)
		(pin "M1"
		)
		(pin "M2"
		)
		(pin "M3"
		)
		(pin "M5"
		)
		(pin "N2"
		)
		(pin "N3"
		)
		(pin "N4"
		)
		(pin "N5"
		)
		(pin "P1"
		)
		(pin "P2"
		)
		(pin "P4"
		)
		(pin "P5"
		)
		(pin "R1"
		)
		(pin "R2"
		)
		(pin "R3"
		)
		(pin "R4"
		)
		(pin "T1"
		)
		(pin "T3"
		)
		(pin "T4"
		)
		(pin "T5"
		)
		(pin "U1"
		)
		(pin "U2"
		)
		(pin "U3"
		)
		(pin "U5"
		)
		(pin "V2"
		)
		(pin "V3"
		)
		(pin "V4"
		)
		(pin "V5"
		)
		(pin "W1"
		)
		(pin "W2"
		)
		(pin "W4"
		)
		(pin "W5"
		)
		(pin "Y1"
		)
		(pin "Y2"
		)
		(pin "Y3"
		)
		(pin "Y4"
		)
		(pin "AA10"
		)
		(pin "AA11"
		)
		(pin "AA13"
		)
		(pin "AA5"
		)
		(pin "AA6"
		)
		(pin "AA8"
		)
		(pin "AA9"
		)
		(pin "AB10"
		)
		(pin "AB7"
		)
		(pin "AB8"
		)
		(pin "R6"
		)
		(pin "R7"
		)
		(pin "T10"
		)
		(pin "T11"
		)
		(pin "T13"
		)
		(pin "T14"
		)
		(pin "T6"
		)
		(pin "T8"
		)
		(pin "T9"
		)
		(pin "U10"
		)
		(pin "U11"
		)
		(pin "U12"
		)
		(pin "U13"
		)
		(pin "U6"
		)
		(pin "U7"
		)
		(pin "U8"
		)
		(pin "V10"
		)
		(pin "V12"
		)
		(pin "V13"
		)
		(pin "V7"
		)
		(pin "V8"
		)
		(pin "V9"
		)
		(pin "W10"
		)
		(pin "W11"
		)
		(pin "W12"
		)
		(pin "W6"
		)
		(pin "W7"
		)
		(pin "W9"
		)
		(pin "Y11"
		)
		(pin "Y12"
		)
		(pin "Y13"
		)
		(pin "Y6"
		)
		(pin "Y7"
		)
		(pin "Y8"
		)
		(pin "Y9"
		)
		(pin "A10"
		)
		(pin "A11"
		)
		(pin "A8"
		)
		(pin "A9"
		)
		(pin "B10"
		)
		(pin "B11"
		)
		(pin "B8"
		)
		(pin "C10"
		)
		(pin "C8"
		)
		(pin "C9"
		)
		(pin "D10"
		)
		(pin "D11"
		)
		(pin "D9"
		)
		(pin "E11"
		)
		(pin "E12"
		)
		(pin "E13"
		)
		(pin "E8"
		)
		(pin "E9"
		)
		(pin "F10"
		)
		(pin "F11"
		)
		(pin "F13"
		)
		(pin "F14"
		)
		(pin "F8"
		)
		(pin "F9"
		)
		(pin "G10"
		)
		(pin "G11"
		)
		(pin "G12"
		)
		(pin "G13"
		)
		(pin "G8"
		)
		(pin "H10"
		)
		(pin "H12"
		)
		(pin "H13"
		)
		(pin "H14"
		)
		(pin "H8"
		)
		(pin "H9"
		)
		(pin "A13"
		)
		(pin "A14"
		)
		(pin "A15"
		)
		(pin "A16"
		)
		(pin "A18"
		)
		(pin "A19"
		)
		(pin "A20"
		)
		(pin "A21"
		)
		(pin "B12"
		)
		(pin "B13"
		)
		(pin "B15"
		)
		(pin "B16"
		)
		(pin "B17"
		)
		(pin "B18"
		)
		(pin "B20"
		)
		(pin "B21"
		)
		(pin "B22"
		)
		(pin "C12"
		)
		(pin "C13"
		)
		(pin "C14"
		)
		(pin "C15"
		)
		(pin "C17"
		)
		(pin "C18"
		)
		(pin "C19"
		)
		(pin "C20"
		)
		(pin "C22"
		)
		(pin "D12"
		)
		(pin "D14"
		)
		(pin "D15"
		)
		(pin "D16"
		)
		(pin "D17"
		)
		(pin "D19"
		)
		(pin "D20"
		)
		(pin "D21"
		)
		(pin "D22"
		)
		(pin "E14"
		)
		(pin "E16"
		)
		(pin "E17"
		)
		(pin "E18"
		)
		(pin "E19"
		)
		(pin "F15"
		)
		(pin "F16"
		)
		(pin "F18"
		)
		(pin "G15"
		)
		(pin "G16"
		)
		(pin "G17"
		)
		(pin "H15"
		)
		(pin "H17"
		)
		(pin "J16"
		)
		(pin "J17"
		)
		(pin "E21"
		)
		(pin "E22"
		)
		(pin "F19"
		)
		(pin "F20"
		)
		(pin "F21"
		)
		(pin "G18"
		)
		(pin "G20"
		)
		(pin "G21"
		)
		(pin "G22"
		)
		(pin "H18"
		)
		(pin "H19"
		)
		(pin "H20"
		)
		(pin "H22"
		)
		(pin "J19"
		)
		(pin "J20"
		)
		(pin "J21"
		)
		(pin "J22"
		)
		(pin "K16"
		)
		(pin "K17"
		)
		(pin "K18"
		)
		(pin "K19"
		)
		(pin "K21"
		)
		(pin "K22"
		)
		(pin "L16"
		)
		(pin "L18"
		)
		(pin "L19"
		)
		(pin "L20"
		)
		(pin "L21"
		)
		(pin "M16"
		)
		(pin "M17"
		)
		(pin "M18"
		)
		(pin "M20"
		)
		(pin "M21"
		)
		(pin "M22"
		)
		(pin "N17"
		)
		(pin "N18"
		)
		(pin "N19"
		)
		(pin "N20"
		)
		(pin "N22"
		)
		(pin "P16"
		)
		(pin "P17"
		)
		(pin "P19"
		)
		(pin "P20"
		)
		(pin "P21"
		)
		(pin "P22"
		)
		(pin "R17"
		)
		(pin "R18"
		)
		(pin "R19"
		)
		(pin "R21"
		)
		(pin "R22"
		)
		(instances
			(project "lpddr4-test-board"
				(path ""
					(reference "U3")
					(unit 9)
				)
			)
		)
	)
	(symbol
		(lib_id "antmicroFPGAChips:XC7K70T-FBG484")
		(at 302.895 41.275 0)
		(unit 5)
		(exclude_from_sim no)
		(in_bom yes)
		(on_board yes)
		(dnp no)
		(property "Reference" "U3"
			(at 307.975 33.02 0)
			(effects
				(font
					(size 1.27 1.27)
					(thickness 0.15)
				)
				(justify left bottom)
			)
		)
		(property "Value" "XC7K70T-FBG484"
			(at 356.235 46.355 0)
			(effects
				(font
					(size 1.27 1.27)
					(thickness 0.15)
				)
				(justify left bottom)
				(hide yes)
			)
		)
		(property "Footprint" "antmicro-footprints:BGA-484_23x23mm_Layout22x22_P1mm_FBG484"
			(at 356.235 48.895 0)
			(effects
				(font
					(size 1.27 1.27)
					(thickness 0.15)
				)
				(justify left bottom)
				(hide yes)
			)
		)
		(property "Datasheet" "https://docs.xilinx.com/v/u/en-US/ds182_Kintex_7_Data_Sheet"
			(at 356.235 51.435 0)
			(effects
				(font
					(size 1.27 1.27)
					(thickness 0.15)
				)
				(justify left bottom)
				(hide yes)
			)
		)
		(property "Description" ""
			(at 302.895 41.275 0)
			(effects
				(font
					(size 1.27 1.27)
				)
			)
		)
		(property "Manufacturer" "AMD-Xilinx"
			(at 356.235 53.975 0)
			(effects
				(font
					(size 1.27 1.27)
					(thickness 0.15)
				)
				(justify left bottom)
				(hide yes)
			)
		)
		(property "MPN" "XC7K70T-1FBG484C"
			(at 356.87 35.56 0)
			(effects
				(font
					(size 1.27 1.27)
					(thickness 0.15)
				)
				(justify left bottom)
			)
		)
		(property "Author" "Antmicro"
			(at 356.235 56.515 0)
			(effects
				(font
					(size 1.27 1.27)
					(thickness 0.15)
				)
				(justify left bottom)
				(hide yes)
			)
		)
		(property "License" "Apache-2.0"
			(at 356.235 59.055 0)
			(effects
				(font
					(size 1.27 1.27)
					(thickness 0.15)
				)
				(justify left bottom)
				(hide yes)
			)
		)
		(pin "AA10"
		)
		(pin "AA11"
		)
		(pin "AA13"
		)
		(pin "AA5"
		)
		(pin "AA6"
		)
		(pin "AA8"
		)
		(pin "AA9"
		)
		(pin "AB10"
		)
		(pin "AB11"
		)
		(pin "AB12"
		)
		(pin "AB13"
		)
		(pin "AB5"
		)
		(pin "AB6"
		)
		(pin "AB7"
		)
		(pin "AB8"
		)
		(pin "R6"
		)
		(pin "R7"
		)
		(pin "T10"
		)
		(pin "T11"
		)
		(pin "T13"
		)
		(pin "T14"
		)
		(pin "T6"
		)
		(pin "T8"
		)
		(pin "T9"
		)
		(pin "U10"
		)
		(pin "U11"
		)
		(pin "U12"
		)
		(pin "U13"
		)
		(pin "U6"
		)
		(pin "U7"
		)
		(pin "U8"
		)
		(pin "V10"
		)
		(pin "V12"
		)
		(pin "V13"
		)
		(pin "V7"
		)
		(pin "V8"
		)
		(pin "V9"
		)
		(pin "W10"
		)
		(pin "W11"
		)
		(pin "W12"
		)
		(pin "W6"
		)
		(pin "W7"
		)
		(pin "W9"
		)
		(pin "Y11"
		)
		(pin "Y12"
		)
		(pin "Y13"
		)
		(pin "Y6"
		)
		(pin "Y7"
		)
		(pin "Y8"
		)
		(pin "Y9"
		)
		(pin "R9"
		)
		(pin "T12"
		)
		(pin "T17"
		)
		(pin "T2"
		)
		(pin "T22"
		)
		(pin "V11"
		)
		(pin "V16"
		)
		(pin "V21"
		)
		(pin "V6"
		)
		(pin "W13"
		)
		(pin "W18"
		)
		(pin "W3"
		)
		(pin "W8"
		)
		(pin "Y10"
		)
		(pin "Y15"
		)
		(pin "Y20"
		)
		(pin "Y5"
		)
		(pin "G7"
		)
		(pin "H6"
		)
		(pin "H7"
		)
		(pin "J5"
		)
		(pin "J6"
		)
		(pin "R11"
		)
		(pin "R12"
		)
		(pin "R10"
		)
		(pin "R13"
		)
		(pin "R14"
		)
		(pin "R15"
		)
		(pin "T7"
		)
		(pin "U14"
		)
		(pin "U19"
		)
		(pin "U4"
		)
		(pin "U9"
		)
		(pin "V1"
		)
		(pin "R20"
		)
		(pin "R5"
		)
		(pin "R8"
		)
		(pin "K6"
		)
		(pin "K7"
		)
		(pin "L11"
		)
		(pin "L12"
		)
		(pin "L6"
		)
		(pin "L7"
		)
		(pin "M11"
		)
		(pin "M12"
		)
		(pin "M6"
		)
		(pin "M7"
		)
		(pin "N11"
		)
		(pin "N12"
		)
		(pin "P6"
		)
		(pin "A3"
		)
		(pin "A4"
		)
		(pin "B1"
		)
		(pin "B2"
		)
		(pin "A1"
		)
		(pin "A12"
		)
		(pin "A17"
		)
		(pin "A2"
		)
		(pin "A22"
		)
		(pin "A5"
		)
		(pin "A6"
		)
		(pin "A7"
		)
		(pin "AA12"
		)
		(pin "AA17"
		)
		(pin "AA2"
		)
		(pin "AA22"
		)
		(pin "AA7"
		)
		(pin "AB14"
		)
		(pin "AB19"
		)
		(pin "AB4"
		)
		(pin "AB9"
		)
		(pin "B14"
		)
		(pin "B19"
		)
		(pin "B3"
		)
		(pin "B4"
		)
		(pin "B7"
		)
		(pin "B9"
		)
		(pin "C1"
		)
		(pin "C11"
		)
		(pin "C16"
		)
		(pin "C2"
		)
		(pin "C21"
		)
		(pin "C5"
		)
		(pin "C6"
		)
		(pin "C7"
		)
		(pin "D13"
		)
		(pin "D18"
		)
		(pin "D3"
		)
		(pin "D4"
		)
		(pin "D7"
		)
		(pin "D8"
		)
		(pin "E1"
		)
		(pin "E10"
		)
		(pin "E15"
		)
		(pin "E2"
		)
		(pin "E20"
		)
		(pin "E5"
		)
		(pin "E6"
		)
		(pin "E7"
		)
		(pin "F12"
		)
		(pin "F17"
		)
		(pin "F22"
		)
		(pin "F3"
		)
		(pin "F4"
		)
		(pin "F7"
		)
		(pin "G1"
		)
		(pin "G14"
		)
		(pin "G19"
		)
		(pin "G2"
		)
		(pin "G5"
		)
		(pin "G6"
		)
		(pin "G9"
		)
		(pin "H1"
		)
		(pin "H11"
		)
		(pin "H16"
		)
		(pin "H2"
		)
		(pin "H21"
		)
		(pin "H3"
		)
		(pin "H4"
		)
		(pin "H5"
		)
		(pin "J1"
		)
		(pin "J10"
		)
		(pin "J11"
		)
		(pin "J12"
		)
		(pin "J13"
		)
		(pin "J14"
		)
		(pin "J15"
		)
		(pin "J18"
		)
		(pin "J2"
		)
		(pin "J3"
		)
		(pin "J4"
		)
		(pin "J7"
		)
		(pin "J8"
		)
		(pin "J9"
		)
		(pin "K10"
		)
		(pin "K11"
		)
		(pin "K12"
		)
		(pin "K13"
		)
		(pin "K14"
		)
		(pin "K15"
		)
		(pin "K20"
		)
		(pin "K5"
		)
		(pin "K8"
		)
		(pin "K9"
		)
		(pin "L10"
		)
		(pin "L13"
		)
		(pin "L14"
		)
		(pin "L15"
		)
		(pin "L17"
		)
		(pin "L2"
		)
		(pin "L22"
		)
		(pin "L8"
		)
		(pin "L9"
		)
		(pin "M10"
		)
		(pin "M13"
		)
		(pin "M14"
		)
		(pin "M15"
		)
		(pin "M19"
		)
		(pin "M4"
		)
		(pin "M8"
		)
		(pin "M9"
		)
		(pin "N1"
		)
		(pin "N10"
		)
		(pin "N13"
		)
		(pin "N14"
		)
		(pin "N15"
		)
		(pin "N16"
		)
		(pin "N21"
		)
		(pin "N6"
		)
		(pin "N7"
		)
		(pin "N8"
		)
		(pin "N9"
		)
		(pin "P10"
		)
		(pin "P11"
		)
		(pin "P12"
		)
		(pin "P13"
		)
		(pin "P14"
		)
		(pin "P15"
		)
		(pin "P18"
		)
		(pin "P3"
		)
		(pin "P7"
		)
		(pin "P8"
		)
		(pin "P9"
		)
		(pin "B5"
		)
		(pin "B6"
		)
		(pin "C3"
		)
		(pin "C4"
		)
		(pin "D1"
		)
		(pin "D2"
		)
		(pin "D5"
		)
		(pin "D6"
		)
		(pin "E3"
		)
		(pin "E4"
		)
		(pin "F1"
		)
		(pin "F2"
		)
		(pin "F5"
		)
		(pin "F6"
		)
		(pin "G3"
		)
		(pin "G4"
		)
		(pin "AA1"
		)
		(pin "AA3"
		)
		(pin "AA4"
		)
		(pin "AB1"
		)
		(pin "AB2"
		)
		(pin "AB3"
		)
		(pin "K1"
		)
		(pin "K2"
		)
		(pin "K3"
		)
		(pin "K4"
		)
		(pin "L1"
		)
		(pin "L3"
		)
		(pin "L4"
		)
		(pin "L5"
		)
		(pin "M1"
		)
		(pin "M2"
		)
		(pin "M3"
		)
		(pin "M5"
		)
		(pin "N2"
		)
		(pin "N3"
		)
		(pin "N4"
		)
		(pin "N5"
		)
		(pin "P1"
		)
		(pin "P2"
		)
		(pin "P4"
		)
		(pin "P5"
		)
		(pin "R1"
		)
		(pin "R2"
		)
		(pin "R3"
		)
		(pin "R4"
		)
		(pin "T1"
		)
		(pin "T3"
		)
		(pin "T4"
		)
		(pin "T5"
		)
		(pin "U1"
		)
		(pin "U2"
		)
		(pin "U3"
		)
		(pin "U5"
		)
		(pin "V2"
		)
		(pin "V3"
		)
		(pin "V4"
		)
		(pin "V5"
		)
		(pin "W1"
		)
		(pin "W2"
		)
		(pin "W4"
		)
		(pin "W5"
		)
		(pin "Y1"
		)
		(pin "Y2"
		)
		(pin "Y3"
		)
		(pin "Y4"
		)
		(pin "A10"
		)
		(pin "A11"
		)
		(pin "A8"
		)
		(pin "A9"
		)
		(pin "B10"
		)
		(pin "B11"
		)
		(pin "B8"
		)
		(pin "C10"
		)
		(pin "C8"
		)
		(pin "C9"
		)
		(pin "D10"
		)
		(pin "D11"
		)
		(pin "D9"
		)
		(pin "E11"
		)
		(pin "E12"
		)
		(pin "E13"
		)
		(pin "E8"
		)
		(pin "E9"
		)
		(pin "F10"
		)
		(pin "F11"
		)
		(pin "F13"
		)
		(pin "F14"
		)
		(pin "F8"
		)
		(pin "F9"
		)
		(pin "G10"
		)
		(pin "G11"
		)
		(pin "G12"
		)
		(pin "G13"
		)
		(pin "G8"
		)
		(pin "H10"
		)
		(pin "H12"
		)
		(pin "H13"
		)
		(pin "H14"
		)
		(pin "H8"
		)
		(pin "H9"
		)
		(pin "A13"
		)
		(pin "A14"
		)
		(pin "A15"
		)
		(pin "A16"
		)
		(pin "A18"
		)
		(pin "A19"
		)
		(pin "A20"
		)
		(pin "A21"
		)
		(pin "B12"
		)
		(pin "B13"
		)
		(pin "B15"
		)
		(pin "B16"
		)
		(pin "B17"
		)
		(pin "B18"
		)
		(pin "B20"
		)
		(pin "B21"
		)
		(pin "B22"
		)
		(pin "C12"
		)
		(pin "C13"
		)
		(pin "C14"
		)
		(pin "C15"
		)
		(pin "C17"
		)
		(pin "C18"
		)
		(pin "C19"
		)
		(pin "C20"
		)
		(pin "C22"
		)
		(pin "D12"
		)
		(pin "D14"
		)
		(pin "D15"
		)
		(pin "D16"
		)
		(pin "D17"
		)
		(pin "D19"
		)
		(pin "D20"
		)
		(pin "D21"
		)
		(pin "D22"
		)
		(pin "E14"
		)
		(pin "E16"
		)
		(pin "E17"
		)
		(pin "E18"
		)
		(pin "E19"
		)
		(pin "F15"
		)
		(pin "F16"
		)
		(pin "F18"
		)
		(pin "G15"
		)
		(pin "G16"
		)
		(pin "G17"
		)
		(pin "H15"
		)
		(pin "H17"
		)
		(pin "J16"
		)
		(pin "J17"
		)
		(pin "E21"
		)
		(pin "E22"
		)
		(pin "F19"
		)
		(pin "F20"
		)
		(pin "F21"
		)
		(pin "G18"
		)
		(pin "G20"
		)
		(pin "G21"
		)
		(pin "G22"
		)
		(pin "H18"
		)
		(pin "H19"
		)
		(pin "H20"
		)
		(pin "H22"
		)
		(pin "J19"
		)
		(pin "J20"
		)
		(pin "J21"
		)
		(pin "J22"
		)
		(pin "K16"
		)
		(pin "K17"
		)
		(pin "K18"
		)
		(pin "K19"
		)
		(pin "K21"
		)
		(pin "K22"
		)
		(pin "L16"
		)
		(pin "L18"
		)
		(pin "L19"
		)
		(pin "L20"
		)
		(pin "L21"
		)
		(pin "M16"
		)
		(pin "M17"
		)
		(pin "M18"
		)
		(pin "M20"
		)
		(pin "M21"
		)
		(pin "M22"
		)
		(pin "N17"
		)
		(pin "N18"
		)
		(pin "N19"
		)
		(pin "N20"
		)
		(pin "N22"
		)
		(pin "P16"
		)
		(pin "P17"
		)
		(pin "P19"
		)
		(pin "P20"
		)
		(pin "P21"
		)
		(pin "P22"
		)
		(pin "R17"
		)
		(pin "R18"
		)
		(pin "R19"
		)
		(pin "R21"
		)
		(pin "R22"
		)
		(pin "AA14"
		)
		(pin "AA15"
		)
		(pin "AA16"
		)
		(pin "AA18"
		)
		(pin "AA19"
		)
		(pin "AA20"
		)
		(pin "AA21"
		)
		(pin "AB15"
		)
		(pin "AB16"
		)
		(pin "AB17"
		)
		(pin "AB18"
		)
		(pin "AB20"
		)
		(pin "AB21"
		)
		(pin "AB22"
		)
		(pin "R16"
		)
		(pin "T15"
		)
		(pin "T16"
		)
		(pin "T18"
		)
		(pin "T19"
		)
		(pin "T20"
		)
		(pin "T21"
		)
		(pin "U15"
		)
		(pin "U16"
		)
		(pin "U17"
		)
		(pin "U18"
		)
		(pin "U20"
		)
		(pin "U21"
		)
		(pin "U22"
		)
		(pin "V14"
		)
		(pin "V15"
		)
		(pin "V17"
		)
		(pin "V18"
		)
		(pin "V19"
		)
		(pin "V20"
		)
		(pin "V22"
		)
		(pin "W14"
		)
		(pin "W15"
		)
		(pin "W16"
		)
		(pin "W17"
		)
		(pin "W19"
		)
		(pin "W20"
		)
		(pin "W21"
		)
		(pin "W22"
		)
		(pin "Y14"
		)
		(pin "Y16"
		)
		(pin "Y17"
		)
		(pin "Y18"
		)
		(pin "Y19"
		)
		(pin "Y21"
		)
		(pin "Y22"
		)
		(instances
			(project "lpddr4-test-board"
				(path ""
					(reference "U3")
					(unit 5)
				)
			)
		)
	)
	(symbol
		(lib_id "antmicroFPGAChips:XC7K70T-FBG484")
		(at 173.355 41.275 0)
		(unit 7)
		(exclude_from_sim no)
		(in_bom yes)
		(on_board yes)
		(dnp no)
		(property "Reference" "U3"
			(at 178.435 33.02 0)
			(effects
				(font
					(size 1.27 1.27)
					(thickness 0.15)
				)
				(justify left bottom)
			)
		)
		(property "Value" "XC7K70T-FBG484"
			(at 226.695 46.355 0)
			(effects
				(font
					(size 1.27 1.27)
					(thickness 0.15)
				)
				(justify left bottom)
				(hide yes)
			)
		)
		(property "Footprint" "antmicro-footprints:BGA-484_23x23mm_Layout22x22_P1mm_FBG484"
			(at 226.695 48.895 0)
			(effects
				(font
					(size 1.27 1.27)
					(thickness 0.15)
				)
				(justify left bottom)
				(hide yes)
			)
		)
		(property "Datasheet" "https://docs.xilinx.com/v/u/en-US/ds182_Kintex_7_Data_Sheet"
			(at 226.695 51.435 0)
			(effects
				(font
					(size 1.27 1.27)
					(thickness 0.15)
				)
				(justify left bottom)
				(hide yes)
			)
		)
		(property "Description" ""
			(at 173.355 41.275 0)
			(effects
				(font
					(size 1.27 1.27)
				)
			)
		)
		(property "Manufacturer" "AMD-Xilinx"
			(at 226.695 53.975 0)
			(effects
				(font
					(size 1.27 1.27)
					(thickness 0.15)
				)
				(justify left bottom)
				(hide yes)
			)
		)
		(property "MPN" "XC7K70T-1FBG484C"
			(at 227.33 35.56 0)
			(effects
				(font
					(size 1.27 1.27)
					(thickness 0.15)
				)
				(justify left bottom)
			)
		)
		(property "Author" "Antmicro"
			(at 226.695 56.515 0)
			(effects
				(font
					(size 1.27 1.27)
					(thickness 0.15)
				)
				(justify left bottom)
				(hide yes)
			)
		)
		(property "License" "Apache-2.0"
			(at 226.695 59.055 0)
			(effects
				(font
					(size 1.27 1.27)
					(thickness 0.15)
				)
				(justify left bottom)
				(hide yes)
			)
		)
		(pin "A13"
		)
		(pin "A14"
		)
		(pin "A15"
		)
		(pin "A16"
		)
		(pin "A18"
		)
		(pin "A19"
		)
		(pin "A20"
		)
		(pin "A21"
		)
		(pin "B12"
		)
		(pin "B13"
		)
		(pin "B15"
		)
		(pin "B16"
		)
		(pin "B17"
		)
		(pin "B18"
		)
		(pin "B20"
		)
		(pin "B21"
		)
		(pin "B22"
		)
		(pin "C12"
		)
		(pin "C13"
		)
		(pin "C14"
		)
		(pin "C15"
		)
		(pin "C17"
		)
		(pin "C18"
		)
		(pin "C19"
		)
		(pin "C20"
		)
		(pin "C22"
		)
		(pin "D12"
		)
		(pin "D14"
		)
		(pin "D15"
		)
		(pin "D16"
		)
		(pin "D17"
		)
		(pin "D19"
		)
		(pin "D20"
		)
		(pin "D21"
		)
		(pin "D22"
		)
		(pin "E14"
		)
		(pin "E16"
		)
		(pin "E17"
		)
		(pin "E18"
		)
		(pin "E19"
		)
		(pin "F15"
		)
		(pin "F16"
		)
		(pin "F18"
		)
		(pin "G15"
		)
		(pin "G16"
		)
		(pin "G17"
		)
		(pin "H15"
		)
		(pin "H17"
		)
		(pin "J16"
		)
		(pin "J17"
		)
		(pin "A1"
		)
		(pin "A12"
		)
		(pin "A17"
		)
		(pin "A2"
		)
		(pin "A22"
		)
		(pin "A5"
		)
		(pin "A6"
		)
		(pin "A7"
		)
		(pin "AA12"
		)
		(pin "AA17"
		)
		(pin "AA2"
		)
		(pin "AA22"
		)
		(pin "AA7"
		)
		(pin "AB14"
		)
		(pin "AB19"
		)
		(pin "AB4"
		)
		(pin "AB9"
		)
		(pin "B14"
		)
		(pin "B19"
		)
		(pin "B3"
		)
		(pin "B4"
		)
		(pin "B7"
		)
		(pin "B9"
		)
		(pin "C1"
		)
		(pin "C11"
		)
		(pin "C16"
		)
		(pin "C2"
		)
		(pin "C21"
		)
		(pin "C5"
		)
		(pin "C6"
		)
		(pin "C7"
		)
		(pin "D13"
		)
		(pin "D18"
		)
		(pin "D3"
		)
		(pin "D4"
		)
		(pin "D7"
		)
		(pin "D8"
		)
		(pin "E1"
		)
		(pin "E10"
		)
		(pin "E15"
		)
		(pin "E2"
		)
		(pin "E20"
		)
		(pin "E5"
		)
		(pin "E6"
		)
		(pin "E7"
		)
		(pin "F12"
		)
		(pin "F17"
		)
		(pin "F22"
		)
		(pin "F3"
		)
		(pin "F4"
		)
		(pin "F7"
		)
		(pin "G1"
		)
		(pin "G14"
		)
		(pin "G19"
		)
		(pin "G2"
		)
		(pin "G5"
		)
		(pin "G6"
		)
		(pin "G9"
		)
		(pin "H1"
		)
		(pin "H11"
		)
		(pin "H16"
		)
		(pin "H2"
		)
		(pin "H21"
		)
		(pin "H3"
		)
		(pin "H4"
		)
		(pin "H5"
		)
		(pin "J1"
		)
		(pin "J10"
		)
		(pin "J11"
		)
		(pin "J12"
		)
		(pin "J13"
		)
		(pin "J14"
		)
		(pin "J15"
		)
		(pin "J18"
		)
		(pin "J2"
		)
		(pin "J3"
		)
		(pin "J4"
		)
		(pin "J7"
		)
		(pin "J8"
		)
		(pin "J9"
		)
		(pin "K10"
		)
		(pin "K11"
		)
		(pin "K12"
		)
		(pin "K13"
		)
		(pin "K14"
		)
		(pin "K15"
		)
		(pin "K20"
		)
		(pin "K5"
		)
		(pin "K8"
		)
		(pin "K9"
		)
		(pin "L10"
		)
		(pin "L13"
		)
		(pin "L14"
		)
		(pin "L15"
		)
		(pin "L17"
		)
		(pin "L2"
		)
		(pin "L22"
		)
		(pin "L8"
		)
		(pin "L9"
		)
		(pin "M10"
		)
		(pin "M13"
		)
		(pin "M14"
		)
		(pin "M15"
		)
		(pin "M19"
		)
		(pin "M4"
		)
		(pin "M8"
		)
		(pin "M9"
		)
		(pin "N1"
		)
		(pin "N10"
		)
		(pin "N13"
		)
		(pin "N14"
		)
		(pin "N15"
		)
		(pin "N16"
		)
		(pin "N21"
		)
		(pin "N6"
		)
		(pin "N7"
		)
		(pin "N8"
		)
		(pin "N9"
		)
		(pin "P10"
		)
		(pin "P11"
		)
		(pin "P12"
		)
		(pin "P13"
		)
		(pin "P14"
		)
		(pin "P15"
		)
		(pin "P18"
		)
		(pin "P3"
		)
		(pin "P7"
		)
		(pin "P8"
		)
		(pin "P9"
		)
		(pin "AB11"
		)
		(pin "AB12"
		)
		(pin "AB13"
		)
		(pin "AB5"
		)
		(pin "AB6"
		)
		(pin "R10"
		)
		(pin "R11"
		)
		(pin "R12"
		)
		(pin "R13"
		)
		(pin "R14"
		)
		(pin "R15"
		)
		(pin "R20"
		)
		(pin "R5"
		)
		(pin "R8"
		)
		(pin "R9"
		)
		(pin "T12"
		)
		(pin "T17"
		)
		(pin "T2"
		)
		(pin "T22"
		)
		(pin "T7"
		)
		(pin "U14"
		)
		(pin "U19"
		)
		(pin "U4"
		)
		(pin "U9"
		)
		(pin "V1"
		)
		(pin "V11"
		)
		(pin "V16"
		)
		(pin "V21"
		)
		(pin "V6"
		)
		(pin "W13"
		)
		(pin "W18"
		)
		(pin "W3"
		)
		(pin "W8"
		)
		(pin "Y10"
		)
		(pin "Y15"
		)
		(pin "Y20"
		)
		(pin "Y5"
		)
		(pin "G7"
		)
		(pin "H6"
		)
		(pin "H7"
		)
		(pin "J5"
		)
		(pin "J6"
		)
		(pin "K6"
		)
		(pin "K7"
		)
		(pin "L11"
		)
		(pin "L12"
		)
		(pin "L6"
		)
		(pin "L7"
		)
		(pin "M11"
		)
		(pin "M12"
		)
		(pin "M6"
		)
		(pin "M7"
		)
		(pin "N11"
		)
		(pin "N12"
		)
		(pin "P6"
		)
		(pin "A3"
		)
		(pin "A4"
		)
		(pin "B1"
		)
		(pin "B2"
		)
		(pin "B5"
		)
		(pin "B6"
		)
		(pin "C3"
		)
		(pin "C4"
		)
		(pin "D1"
		)
		(pin "D2"
		)
		(pin "D5"
		)
		(pin "D6"
		)
		(pin "E3"
		)
		(pin "E4"
		)
		(pin "F1"
		)
		(pin "F2"
		)
		(pin "F5"
		)
		(pin "F6"
		)
		(pin "G3"
		)
		(pin "G4"
		)
		(pin "AA1"
		)
		(pin "AA3"
		)
		(pin "AA4"
		)
		(pin "AB1"
		)
		(pin "AB2"
		)
		(pin "AB3"
		)
		(pin "K1"
		)
		(pin "K2"
		)
		(pin "K3"
		)
		(pin "K4"
		)
		(pin "L1"
		)
		(pin "L3"
		)
		(pin "L4"
		)
		(pin "L5"
		)
		(pin "M1"
		)
		(pin "M2"
		)
		(pin "M3"
		)
		(pin "M5"
		)
		(pin "N2"
		)
		(pin "N3"
		)
		(pin "N4"
		)
		(pin "N5"
		)
		(pin "P1"
		)
		(pin "P2"
		)
		(pin "P4"
		)
		(pin "P5"
		)
		(pin "R1"
		)
		(pin "R2"
		)
		(pin "R3"
		)
		(pin "R4"
		)
		(pin "T1"
		)
		(pin "T3"
		)
		(pin "T4"
		)
		(pin "T5"
		)
		(pin "U1"
		)
		(pin "U2"
		)
		(pin "U3"
		)
		(pin "U5"
		)
		(pin "V2"
		)
		(pin "V3"
		)
		(pin "V4"
		)
		(pin "V5"
		)
		(pin "W1"
		)
		(pin "W2"
		)
		(pin "W4"
		)
		(pin "W5"
		)
		(pin "Y1"
		)
		(pin "Y2"
		)
		(pin "Y3"
		)
		(pin "Y4"
		)
		(pin "AA10"
		)
		(pin "AA11"
		)
		(pin "AA13"
		)
		(pin "AA5"
		)
		(pin "AA6"
		)
		(pin "AA8"
		)
		(pin "AA9"
		)
		(pin "AB10"
		)
		(pin "AB7"
		)
		(pin "AB8"
		)
		(pin "R6"
		)
		(pin "R7"
		)
		(pin "T10"
		)
		(pin "T11"
		)
		(pin "T13"
		)
		(pin "T14"
		)
		(pin "T6"
		)
		(pin "T8"
		)
		(pin "T9"
		)
		(pin "U10"
		)
		(pin "U11"
		)
		(pin "U12"
		)
		(pin "U13"
		)
		(pin "U6"
		)
		(pin "U7"
		)
		(pin "U8"
		)
		(pin "V10"
		)
		(pin "V12"
		)
		(pin "V13"
		)
		(pin "V7"
		)
		(pin "V8"
		)
		(pin "V9"
		)
		(pin "W10"
		)
		(pin "W11"
		)
		(pin "W12"
		)
		(pin "W6"
		)
		(pin "W7"
		)
		(pin "W9"
		)
		(pin "Y11"
		)
		(pin "Y12"
		)
		(pin "Y13"
		)
		(pin "Y6"
		)
		(pin "Y7"
		)
		(pin "Y8"
		)
		(pin "Y9"
		)
		(pin "A10"
		)
		(pin "A11"
		)
		(pin "A8"
		)
		(pin "A9"
		)
		(pin "B10"
		)
		(pin "B11"
		)
		(pin "B8"
		)
		(pin "C10"
		)
		(pin "C8"
		)
		(pin "C9"
		)
		(pin "D10"
		)
		(pin "D11"
		)
		(pin "D9"
		)
		(pin "E11"
		)
		(pin "E12"
		)
		(pin "E13"
		)
		(pin "E8"
		)
		(pin "E9"
		)
		(pin "F10"
		)
		(pin "F11"
		)
		(pin "F13"
		)
		(pin "F14"
		)
		(pin "F8"
		)
		(pin "F9"
		)
		(pin "G10"
		)
		(pin "G11"
		)
		(pin "G12"
		)
		(pin "G13"
		)
		(pin "G8"
		)
		(pin "H10"
		)
		(pin "H12"
		)
		(pin "H13"
		)
		(pin "H14"
		)
		(pin "H8"
		)
		(pin "H9"
		)
		(pin "E21"
		)
		(pin "E22"
		)
		(pin "F19"
		)
		(pin "F20"
		)
		(pin "F21"
		)
		(pin "G18"
		)
		(pin "G20"
		)
		(pin "G21"
		)
		(pin "G22"
		)
		(pin "H18"
		)
		(pin "H19"
		)
		(pin "H20"
		)
		(pin "H22"
		)
		(pin "J19"
		)
		(pin "J20"
		)
		(pin "J21"
		)
		(pin "J22"
		)
		(pin "K16"
		)
		(pin "K17"
		)
		(pin "K18"
		)
		(pin "K19"
		)
		(pin "K21"
		)
		(pin "K22"
		)
		(pin "L16"
		)
		(pin "L18"
		)
		(pin "L19"
		)
		(pin "L20"
		)
		(pin "L21"
		)
		(pin "M16"
		)
		(pin "M17"
		)
		(pin "M18"
		)
		(pin "M20"
		)
		(pin "M21"
		)
		(pin "M22"
		)
		(pin "N17"
		)
		(pin "N18"
		)
		(pin "N19"
		)
		(pin "N20"
		)
		(pin "N22"
		)
		(pin "P16"
		)
		(pin "P17"
		)
		(pin "P19"
		)
		(pin "P20"
		)
		(pin "P21"
		)
		(pin "P22"
		)
		(pin "R17"
		)
		(pin "R18"
		)
		(pin "R19"
		)
		(pin "R21"
		)
		(pin "R22"
		)
		(pin "AA14"
		)
		(pin "AA15"
		)
		(pin "AA16"
		)
		(pin "AA18"
		)
		(pin "AA19"
		)
		(pin "AA20"
		)
		(pin "AA21"
		)
		(pin "AB15"
		)
		(pin "AB16"
		)
		(pin "AB17"
		)
		(pin "AB18"
		)
		(pin "AB20"
		)
		(pin "AB21"
		)
		(pin "AB22"
		)
		(pin "R16"
		)
		(pin "T15"
		)
		(pin "T16"
		)
		(pin "T18"
		)
		(pin "T19"
		)
		(pin "T20"
		)
		(pin "T21"
		)
		(pin "U15"
		)
		(pin "U16"
		)
		(pin "U17"
		)
		(pin "U18"
		)
		(pin "U20"
		)
		(pin "U21"
		)
		(pin "U22"
		)
		(pin "V14"
		)
		(pin "V15"
		)
		(pin "V17"
		)
		(pin "V18"
		)
		(pin "V19"
		)
		(pin "V20"
		)
		(pin "V22"
		)
		(pin "W14"
		)
		(pin "W15"
		)
		(pin "W16"
		)
		(pin "W17"
		)
		(pin "W19"
		)
		(pin "W20"
		)
		(pin "W21"
		)
		(pin "W22"
		)
		(pin "Y14"
		)
		(pin "Y16"
		)
		(pin "Y17"
		)
		(pin "Y18"
		)
		(pin "Y19"
		)
		(pin "Y21"
		)
		(pin "Y22"
		)
		(instances
			(project "lpddr4-test-board"
				(path ""
					(reference "U3")
					(unit 7)
				)
			)
		)
	)
	(symbol
		(lib_id "antmicroFPGAChips:XC7K70T-FBG484")
		(at 191.77 217.17 0)
		(unit 3)
		(exclude_from_sim no)
		(in_bom yes)
		(on_board yes)
		(dnp no)
		(property "Reference" "U3"
			(at 196.85 208.915 0)
			(effects
				(font
					(size 1.27 1.27)
					(thickness 0.15)
				)
				(justify left bottom)
			)
		)
		(property "Value" "XC7K70T-FBG484"
			(at 245.11 222.25 0)
			(effects
				(font
					(size 1.27 1.27)
					(thickness 0.15)
				)
				(justify left bottom)
				(hide yes)
			)
		)
		(property "Footprint" "antmicro-footprints:BGA-484_23x23mm_Layout22x22_P1mm_FBG484"
			(at 245.11 224.79 0)
			(effects
				(font
					(size 1.27 1.27)
					(thickness 0.15)
				)
				(justify left bottom)
				(hide yes)
			)
		)
		(property "Datasheet" "https://docs.xilinx.com/v/u/en-US/ds182_Kintex_7_Data_Sheet"
			(at 245.11 227.33 0)
			(effects
				(font
					(size 1.27 1.27)
					(thickness 0.15)
				)
				(justify left bottom)
				(hide yes)
			)
		)
		(property "Description" ""
			(at 191.77 217.17 0)
			(effects
				(font
					(size 1.27 1.27)
				)
			)
		)
		(property "Manufacturer" "AMD-Xilinx"
			(at 245.11 229.87 0)
			(effects
				(font
					(size 1.27 1.27)
					(thickness 0.15)
				)
				(justify left bottom)
				(hide yes)
			)
		)
		(property "MPN" "XC7K70T-1FBG484C"
			(at 196.85 210.82 0)
			(effects
				(font
					(size 1.27 1.27)
					(thickness 0.15)
				)
				(justify left bottom)
			)
		)
		(property "Author" "Antmicro"
			(at 245.11 232.41 0)
			(effects
				(font
					(size 1.27 1.27)
					(thickness 0.15)
				)
				(justify left bottom)
				(hide yes)
			)
		)
		(property "License" "Apache-2.0"
			(at 245.11 234.95 0)
			(effects
				(font
					(size 1.27 1.27)
					(thickness 0.15)
				)
				(justify left bottom)
				(hide yes)
			)
		)
		(pin "A3"
		)
		(pin "A4"
		)
		(pin "B1"
		)
		(pin "B2"
		)
		(pin "B5"
		)
		(pin "B6"
		)
		(pin "C3"
		)
		(pin "C4"
		)
		(pin "D1"
		)
		(pin "D2"
		)
		(pin "D5"
		)
		(pin "D6"
		)
		(pin "E3"
		)
		(pin "E4"
		)
		(pin "F1"
		)
		(pin "F2"
		)
		(pin "F5"
		)
		(pin "F6"
		)
		(pin "G3"
		)
		(pin "G4"
		)
		(pin "R11"
		)
		(pin "R12"
		)
		(pin "AB11"
		)
		(pin "AB12"
		)
		(pin "AB13"
		)
		(pin "AB5"
		)
		(pin "AB6"
		)
		(pin "R15"
		)
		(pin "R20"
		)
		(pin "R5"
		)
		(pin "R8"
		)
		(pin "R9"
		)
		(pin "T12"
		)
		(pin "T17"
		)
		(pin "T2"
		)
		(pin "T22"
		)
		(pin "T7"
		)
		(pin "U14"
		)
		(pin "U19"
		)
		(pin "R13"
		)
		(pin "R14"
		)
		(pin "R10"
		)
		(pin "U4"
		)
		(pin "U9"
		)
		(pin "V1"
		)
		(pin "V11"
		)
		(pin "V16"
		)
		(pin "V21"
		)
		(pin "V6"
		)
		(pin "W13"
		)
		(pin "W18"
		)
		(pin "W3"
		)
		(pin "W8"
		)
		(pin "Y10"
		)
		(pin "Y15"
		)
		(pin "Y20"
		)
		(pin "Y5"
		)
		(pin "G7"
		)
		(pin "H6"
		)
		(pin "H7"
		)
		(pin "J5"
		)
		(pin "J6"
		)
		(pin "K6"
		)
		(pin "K7"
		)
		(pin "L11"
		)
		(pin "L12"
		)
		(pin "L6"
		)
		(pin "L7"
		)
		(pin "M11"
		)
		(pin "M12"
		)
		(pin "M6"
		)
		(pin "M7"
		)
		(pin "N11"
		)
		(pin "N12"
		)
		(pin "P6"
		)
		(pin "A1"
		)
		(pin "A12"
		)
		(pin "A17"
		)
		(pin "A2"
		)
		(pin "A22"
		)
		(pin "A5"
		)
		(pin "A6"
		)
		(pin "A7"
		)
		(pin "AA12"
		)
		(pin "AA17"
		)
		(pin "AA2"
		)
		(pin "AA22"
		)
		(pin "AA7"
		)
		(pin "AB14"
		)
		(pin "AB19"
		)
		(pin "AB4"
		)
		(pin "AB9"
		)
		(pin "B14"
		)
		(pin "B19"
		)
		(pin "B3"
		)
		(pin "B4"
		)
		(pin "B7"
		)
		(pin "B9"
		)
		(pin "C1"
		)
		(pin "C11"
		)
		(pin "C16"
		)
		(pin "C2"
		)
		(pin "C21"
		)
		(pin "C5"
		)
		(pin "C6"
		)
		(pin "C7"
		)
		(pin "D13"
		)
		(pin "D18"
		)
		(pin "D3"
		)
		(pin "D4"
		)
		(pin "D7"
		)
		(pin "D8"
		)
		(pin "E1"
		)
		(pin "E10"
		)
		(pin "E15"
		)
		(pin "E2"
		)
		(pin "E20"
		)
		(pin "E5"
		)
		(pin "E6"
		)
		(pin "E7"
		)
		(pin "F12"
		)
		(pin "F17"
		)
		(pin "F22"
		)
		(pin "F3"
		)
		(pin "F4"
		)
		(pin "F7"
		)
		(pin "G1"
		)
		(pin "G14"
		)
		(pin "G19"
		)
		(pin "G2"
		)
		(pin "G5"
		)
		(pin "G6"
		)
		(pin "G9"
		)
		(pin "H1"
		)
		(pin "H11"
		)
		(pin "H16"
		)
		(pin "H2"
		)
		(pin "H21"
		)
		(pin "H3"
		)
		(pin "H4"
		)
		(pin "H5"
		)
		(pin "J1"
		)
		(pin "J10"
		)
		(pin "J11"
		)
		(pin "J12"
		)
		(pin "J13"
		)
		(pin "J14"
		)
		(pin "J15"
		)
		(pin "J18"
		)
		(pin "J2"
		)
		(pin "J3"
		)
		(pin "J4"
		)
		(pin "J7"
		)
		(pin "J8"
		)
		(pin "J9"
		)
		(pin "K10"
		)
		(pin "K11"
		)
		(pin "K12"
		)
		(pin "K13"
		)
		(pin "K14"
		)
		(pin "K15"
		)
		(pin "K20"
		)
		(pin "K5"
		)
		(pin "K8"
		)
		(pin "K9"
		)
		(pin "L10"
		)
		(pin "L13"
		)
		(pin "L14"
		)
		(pin "L15"
		)
		(pin "L17"
		)
		(pin "L2"
		)
		(pin "L22"
		)
		(pin "L8"
		)
		(pin "L9"
		)
		(pin "M10"
		)
		(pin "M13"
		)
		(pin "M14"
		)
		(pin "M15"
		)
		(pin "M19"
		)
		(pin "M4"
		)
		(pin "M8"
		)
		(pin "M9"
		)
		(pin "N1"
		)
		(pin "N10"
		)
		(pin "N13"
		)
		(pin "N14"
		)
		(pin "N15"
		)
		(pin "N16"
		)
		(pin "N21"
		)
		(pin "N6"
		)
		(pin "N7"
		)
		(pin "N8"
		)
		(pin "N9"
		)
		(pin "P10"
		)
		(pin "P11"
		)
		(pin "P12"
		)
		(pin "P13"
		)
		(pin "P14"
		)
		(pin "P15"
		)
		(pin "P18"
		)
		(pin "P3"
		)
		(pin "P7"
		)
		(pin "P8"
		)
		(pin "P9"
		)
		(pin "AA1"
		)
		(pin "AA3"
		)
		(pin "AA4"
		)
		(pin "AB1"
		)
		(pin "AB2"
		)
		(pin "AB3"
		)
		(pin "K1"
		)
		(pin "K2"
		)
		(pin "K3"
		)
		(pin "K4"
		)
		(pin "L1"
		)
		(pin "L3"
		)
		(pin "L4"
		)
		(pin "L5"
		)
		(pin "M1"
		)
		(pin "M2"
		)
		(pin "M3"
		)
		(pin "M5"
		)
		(pin "N2"
		)
		(pin "N3"
		)
		(pin "N4"
		)
		(pin "N5"
		)
		(pin "P1"
		)
		(pin "P2"
		)
		(pin "P4"
		)
		(pin "P5"
		)
		(pin "R1"
		)
		(pin "R2"
		)
		(pin "R3"
		)
		(pin "R4"
		)
		(pin "T1"
		)
		(pin "T3"
		)
		(pin "T4"
		)
		(pin "T5"
		)
		(pin "U1"
		)
		(pin "U2"
		)
		(pin "U3"
		)
		(pin "U5"
		)
		(pin "V2"
		)
		(pin "V3"
		)
		(pin "V4"
		)
		(pin "V5"
		)
		(pin "W1"
		)
		(pin "W2"
		)
		(pin "W4"
		)
		(pin "W5"
		)
		(pin "Y1"
		)
		(pin "Y2"
		)
		(pin "Y3"
		)
		(pin "Y4"
		)
		(pin "AA10"
		)
		(pin "AA11"
		)
		(pin "AA13"
		)
		(pin "AA5"
		)
		(pin "AA6"
		)
		(pin "AA8"
		)
		(pin "AA9"
		)
		(pin "AB10"
		)
		(pin "AB7"
		)
		(pin "AB8"
		)
		(pin "R6"
		)
		(pin "R7"
		)
		(pin "T10"
		)
		(pin "T11"
		)
		(pin "T13"
		)
		(pin "T14"
		)
		(pin "T6"
		)
		(pin "T8"
		)
		(pin "T9"
		)
		(pin "U10"
		)
		(pin "U11"
		)
		(pin "U12"
		)
		(pin "U13"
		)
		(pin "U6"
		)
		(pin "U7"
		)
		(pin "U8"
		)
		(pin "V10"
		)
		(pin "V12"
		)
		(pin "V13"
		)
		(pin "V7"
		)
		(pin "V8"
		)
		(pin "V9"
		)
		(pin "W10"
		)
		(pin "W11"
		)
		(pin "W12"
		)
		(pin "W6"
		)
		(pin "W7"
		)
		(pin "W9"
		)
		(pin "Y11"
		)
		(pin "Y12"
		)
		(pin "Y13"
		)
		(pin "Y6"
		)
		(pin "Y7"
		)
		(pin "Y8"
		)
		(pin "Y9"
		)
		(pin "A10"
		)
		(pin "A11"
		)
		(pin "A8"
		)
		(pin "A9"
		)
		(pin "B10"
		)
		(pin "B11"
		)
		(pin "B8"
		)
		(pin "C10"
		)
		(pin "C8"
		)
		(pin "C9"
		)
		(pin "D10"
		)
		(pin "D11"
		)
		(pin "D9"
		)
		(pin "E11"
		)
		(pin "E12"
		)
		(pin "E13"
		)
		(pin "E8"
		)
		(pin "E9"
		)
		(pin "F10"
		)
		(pin "F11"
		)
		(pin "F13"
		)
		(pin "F14"
		)
		(pin "F8"
		)
		(pin "F9"
		)
		(pin "G10"
		)
		(pin "G11"
		)
		(pin "G12"
		)
		(pin "G13"
		)
		(pin "G8"
		)
		(pin "H10"
		)
		(pin "H12"
		)
		(pin "H13"
		)
		(pin "H14"
		)
		(pin "H8"
		)
		(pin "H9"
		)
		(pin "A13"
		)
		(pin "A14"
		)
		(pin "A15"
		)
		(pin "A16"
		)
		(pin "A18"
		)
		(pin "A19"
		)
		(pin "A20"
		)
		(pin "A21"
		)
		(pin "B12"
		)
		(pin "B13"
		)
		(pin "B15"
		)
		(pin "B16"
		)
		(pin "B17"
		)
		(pin "B18"
		)
		(pin "B20"
		)
		(pin "B21"
		)
		(pin "B22"
		)
		(pin "C12"
		)
		(pin "C13"
		)
		(pin "C14"
		)
		(pin "C15"
		)
		(pin "C17"
		)
		(pin "C18"
		)
		(pin "C19"
		)
		(pin "C20"
		)
		(pin "C22"
		)
		(pin "D12"
		)
		(pin "D14"
		)
		(pin "D15"
		)
		(pin "D16"
		)
		(pin "D17"
		)
		(pin "D19"
		)
		(pin "D20"
		)
		(pin "D21"
		)
		(pin "D22"
		)
		(pin "E14"
		)
		(pin "E16"
		)
		(pin "E17"
		)
		(pin "E18"
		)
		(pin "E19"
		)
		(pin "F15"
		)
		(pin "F16"
		)
		(pin "F18"
		)
		(pin "G15"
		)
		(pin "G16"
		)
		(pin "G17"
		)
		(pin "H15"
		)
		(pin "H17"
		)
		(pin "J16"
		)
		(pin "J17"
		)
		(pin "E21"
		)
		(pin "E22"
		)
		(pin "F19"
		)
		(pin "F20"
		)
		(pin "F21"
		)
		(pin "G18"
		)
		(pin "G20"
		)
		(pin "G21"
		)
		(pin "G22"
		)
		(pin "H18"
		)
		(pin "H19"
		)
		(pin "H20"
		)
		(pin "H22"
		)
		(pin "J19"
		)
		(pin "J20"
		)
		(pin "J21"
		)
		(pin "J22"
		)
		(pin "K16"
		)
		(pin "K17"
		)
		(pin "K18"
		)
		(pin "K19"
		)
		(pin "K21"
		)
		(pin "K22"
		)
		(pin "L16"
		)
		(pin "L18"
		)
		(pin "L19"
		)
		(pin "L20"
		)
		(pin "L21"
		)
		(pin "M16"
		)
		(pin "M17"
		)
		(pin "M18"
		)
		(pin "M20"
		)
		(pin "M21"
		)
		(pin "M22"
		)
		(pin "N17"
		)
		(pin "N18"
		)
		(pin "N19"
		)
		(pin "N20"
		)
		(pin "N22"
		)
		(pin "P16"
		)
		(pin "P17"
		)
		(pin "P19"
		)
		(pin "P20"
		)
		(pin "P21"
		)
		(pin "P22"
		)
		(pin "R17"
		)
		(pin "R18"
		)
		(pin "R19"
		)
		(pin "R21"
		)
		(pin "R22"
		)
		(pin "AA14"
		)
		(pin "AA15"
		)
		(pin "AA16"
		)
		(pin "AA18"
		)
		(pin "AA19"
		)
		(pin "AA20"
		)
		(pin "AA21"
		)
		(pin "AB15"
		)
		(pin "AB16"
		)
		(pin "AB17"
		)
		(pin "AB18"
		)
		(pin "AB20"
		)
		(pin "AB21"
		)
		(pin "AB22"
		)
		(pin "R16"
		)
		(pin "T15"
		)
		(pin "T16"
		)
		(pin "T18"
		)
		(pin "T19"
		)
		(pin "T20"
		)
		(pin "T21"
		)
		(pin "U15"
		)
		(pin "U16"
		)
		(pin "U17"
		)
		(pin "U18"
		)
		(pin "U20"
		)
		(pin "U21"
		)
		(pin "U22"
		)
		(pin "V14"
		)
		(pin "V15"
		)
		(pin "V17"
		)
		(pin "V18"
		)
		(pin "V19"
		)
		(pin "V20"
		)
		(pin "V22"
		)
		(pin "W14"
		)
		(pin "W15"
		)
		(pin "W16"
		)
		(pin "W17"
		)
		(pin "W19"
		)
		(pin "W20"
		)
		(pin "W21"
		)
		(pin "W22"
		)
		(pin "Y14"
		)
		(pin "Y16"
		)
		(pin "Y17"
		)
		(pin "Y18"
		)
		(pin "Y19"
		)
		(pin "Y21"
		)
		(pin "Y22"
		)
		(instances
			(project "lpddr4-test-board"
				(path ""
					(reference "U3")
					(unit 3)
				)
			)
		)
	)
	(symbol
		(lib_id "antmicroFPGAChips:XC7K70T-FBG484")
		(at 116.84 41.275 0)
		(mirror y)
		(unit 8)
		(exclude_from_sim no)
		(in_bom yes)
		(on_board yes)
		(dnp no)
		(property "Reference" "U3"
			(at 111.76 33.02 0)
			(effects
				(font
					(size 1.27 1.27)
					(thickness 0.15)
				)
				(justify left bottom)
			)
		)
		(property "Value" "XC7K70T-FBG484"
			(at 63.5 46.355 0)
			(effects
				(font
					(size 1.27 1.27)
					(thickness 0.15)
				)
				(justify left bottom)
				(hide yes)
			)
		)
		(property "Footprint" "antmicro-footprints:BGA-484_23x23mm_Layout22x22_P1mm_FBG484"
			(at 63.5 48.895 0)
			(effects
				(font
					(size 1.27 1.27)
					(thickness 0.15)
				)
				(justify left bottom)
				(hide yes)
			)
		)
		(property "Datasheet" "https://docs.xilinx.com/v/u/en-US/ds182_Kintex_7_Data_Sheet"
			(at 63.5 51.435 0)
			(effects
				(font
					(size 1.27 1.27)
					(thickness 0.15)
				)
				(justify left bottom)
				(hide yes)
			)
		)
		(property "Description" ""
			(at 116.84 41.275 0)
			(effects
				(font
					(size 1.27 1.27)
				)
			)
		)
		(property "Manufacturer" "AMD-Xilinx"
			(at 63.5 53.975 0)
			(effects
				(font
					(size 1.27 1.27)
					(thickness 0.15)
				)
				(justify left bottom)
				(hide yes)
			)
		)
		(property "MPN" "XC7K70T-1FBG484C"
			(at 62.23 35.56 0)
			(effects
				(font
					(size 1.27 1.27)
					(thickness 0.15)
				)
				(justify left bottom)
			)
		)
		(property "Author" "Antmicro"
			(at 63.5 56.515 0)
			(effects
				(font
					(size 1.27 1.27)
					(thickness 0.15)
				)
				(justify left bottom)
				(hide yes)
			)
		)
		(property "License" "Apache-2.0"
			(at 63.5 59.055 0)
			(effects
				(font
					(size 1.27 1.27)
					(thickness 0.15)
				)
				(justify left bottom)
				(hide yes)
			)
		)
		(pin "E21"
		)
		(pin "E22"
		)
		(pin "F19"
		)
		(pin "F20"
		)
		(pin "F21"
		)
		(pin "G18"
		)
		(pin "G20"
		)
		(pin "G21"
		)
		(pin "G22"
		)
		(pin "H18"
		)
		(pin "H19"
		)
		(pin "H20"
		)
		(pin "H22"
		)
		(pin "J19"
		)
		(pin "J20"
		)
		(pin "J21"
		)
		(pin "J22"
		)
		(pin "K16"
		)
		(pin "K17"
		)
		(pin "K18"
		)
		(pin "K19"
		)
		(pin "K21"
		)
		(pin "K22"
		)
		(pin "L16"
		)
		(pin "L18"
		)
		(pin "L19"
		)
		(pin "L20"
		)
		(pin "L21"
		)
		(pin "M16"
		)
		(pin "M17"
		)
		(pin "M18"
		)
		(pin "M20"
		)
		(pin "M21"
		)
		(pin "M22"
		)
		(pin "N17"
		)
		(pin "N18"
		)
		(pin "N19"
		)
		(pin "N20"
		)
		(pin "N22"
		)
		(pin "P16"
		)
		(pin "P17"
		)
		(pin "P19"
		)
		(pin "P20"
		)
		(pin "P21"
		)
		(pin "P22"
		)
		(pin "R17"
		)
		(pin "R18"
		)
		(pin "R19"
		)
		(pin "R21"
		)
		(pin "R22"
		)
		(pin "K5"
		)
		(pin "K8"
		)
		(pin "K9"
		)
		(pin "L10"
		)
		(pin "L13"
		)
		(pin "L14"
		)
		(pin "L15"
		)
		(pin "L17"
		)
		(pin "L2"
		)
		(pin "L22"
		)
		(pin "L8"
		)
		(pin "L9"
		)
		(pin "M10"
		)
		(pin "M13"
		)
		(pin "M14"
		)
		(pin "M15"
		)
		(pin "M19"
		)
		(pin "M4"
		)
		(pin "M8"
		)
		(pin "M9"
		)
		(pin "N1"
		)
		(pin "N10"
		)
		(pin "N13"
		)
		(pin "N14"
		)
		(pin "N15"
		)
		(pin "N16"
		)
		(pin "N21"
		)
		(pin "N6"
		)
		(pin "N7"
		)
		(pin "N8"
		)
		(pin "N9"
		)
		(pin "P10"
		)
		(pin "P11"
		)
		(pin "P12"
		)
		(pin "P13"
		)
		(pin "P14"
		)
		(pin "P15"
		)
		(pin "P18"
		)
		(pin "P3"
		)
		(pin "P7"
		)
		(pin "P8"
		)
		(pin "P9"
		)
		(pin "AB11"
		)
		(pin "AB12"
		)
		(pin "AB13"
		)
		(pin "AB5"
		)
		(pin "AB6"
		)
		(pin "R10"
		)
		(pin "R11"
		)
		(pin "R12"
		)
		(pin "R13"
		)
		(pin "R14"
		)
		(pin "A1"
		)
		(pin "A12"
		)
		(pin "A17"
		)
		(pin "A2"
		)
		(pin "A22"
		)
		(pin "A5"
		)
		(pin "A6"
		)
		(pin "A7"
		)
		(pin "AA12"
		)
		(pin "AA17"
		)
		(pin "AA2"
		)
		(pin "AA22"
		)
		(pin "AA7"
		)
		(pin "AB14"
		)
		(pin "AB19"
		)
		(pin "AB4"
		)
		(pin "AB9"
		)
		(pin "B14"
		)
		(pin "B19"
		)
		(pin "B3"
		)
		(pin "B4"
		)
		(pin "B7"
		)
		(pin "B9"
		)
		(pin "C1"
		)
		(pin "C11"
		)
		(pin "C16"
		)
		(pin "C2"
		)
		(pin "C21"
		)
		(pin "C5"
		)
		(pin "C6"
		)
		(pin "C7"
		)
		(pin "D13"
		)
		(pin "D18"
		)
		(pin "D3"
		)
		(pin "D4"
		)
		(pin "D7"
		)
		(pin "D8"
		)
		(pin "E1"
		)
		(pin "E10"
		)
		(pin "E15"
		)
		(pin "E2"
		)
		(pin "E20"
		)
		(pin "E5"
		)
		(pin "E6"
		)
		(pin "E7"
		)
		(pin "F12"
		)
		(pin "F17"
		)
		(pin "F22"
		)
		(pin "F3"
		)
		(pin "F4"
		)
		(pin "F7"
		)
		(pin "G1"
		)
		(pin "G14"
		)
		(pin "G19"
		)
		(pin "G2"
		)
		(pin "G5"
		)
		(pin "G6"
		)
		(pin "G9"
		)
		(pin "H1"
		)
		(pin "H11"
		)
		(pin "H16"
		)
		(pin "H2"
		)
		(pin "H21"
		)
		(pin "H3"
		)
		(pin "H4"
		)
		(pin "H5"
		)
		(pin "J1"
		)
		(pin "J10"
		)
		(pin "J11"
		)
		(pin "J12"
		)
		(pin "J13"
		)
		(pin "J14"
		)
		(pin "J15"
		)
		(pin "J18"
		)
		(pin "J2"
		)
		(pin "J3"
		)
		(pin "J4"
		)
		(pin "J7"
		)
		(pin "J8"
		)
		(pin "J9"
		)
		(pin "K10"
		)
		(pin "K11"
		)
		(pin "K12"
		)
		(pin "K13"
		)
		(pin "K14"
		)
		(pin "K15"
		)
		(pin "K20"
		)
		(pin "R15"
		)
		(pin "R20"
		)
		(pin "R5"
		)
		(pin "R8"
		)
		(pin "R9"
		)
		(pin "T12"
		)
		(pin "T17"
		)
		(pin "T2"
		)
		(pin "T22"
		)
		(pin "T7"
		)
		(pin "U14"
		)
		(pin "U19"
		)
		(pin "U4"
		)
		(pin "U9"
		)
		(pin "V1"
		)
		(pin "V11"
		)
		(pin "V16"
		)
		(pin "V21"
		)
		(pin "V6"
		)
		(pin "W13"
		)
		(pin "W18"
		)
		(pin "W3"
		)
		(pin "W8"
		)
		(pin "Y10"
		)
		(pin "Y15"
		)
		(pin "Y20"
		)
		(pin "Y5"
		)
		(pin "G7"
		)
		(pin "H6"
		)
		(pin "H7"
		)
		(pin "J5"
		)
		(pin "J6"
		)
		(pin "K6"
		)
		(pin "K7"
		)
		(pin "L11"
		)
		(pin "L12"
		)
		(pin "L6"
		)
		(pin "L7"
		)
		(pin "M11"
		)
		(pin "M12"
		)
		(pin "M6"
		)
		(pin "M7"
		)
		(pin "N11"
		)
		(pin "N12"
		)
		(pin "P6"
		)
		(pin "A3"
		)
		(pin "A4"
		)
		(pin "B1"
		)
		(pin "B2"
		)
		(pin "B5"
		)
		(pin "B6"
		)
		(pin "C3"
		)
		(pin "C4"
		)
		(pin "D1"
		)
		(pin "D2"
		)
		(pin "D5"
		)
		(pin "D6"
		)
		(pin "E3"
		)
		(pin "E4"
		)
		(pin "F1"
		)
		(pin "F2"
		)
		(pin "F5"
		)
		(pin "F6"
		)
		(pin "G3"
		)
		(pin "G4"
		)
		(pin "AA1"
		)
		(pin "AA3"
		)
		(pin "AA4"
		)
		(pin "AB1"
		)
		(pin "AB2"
		)
		(pin "AB3"
		)
		(pin "K1"
		)
		(pin "K2"
		)
		(pin "K3"
		)
		(pin "K4"
		)
		(pin "L1"
		)
		(pin "L3"
		)
		(pin "L4"
		)
		(pin "L5"
		)
		(pin "M1"
		)
		(pin "M2"
		)
		(pin "M3"
		)
		(pin "M5"
		)
		(pin "N2"
		)
		(pin "N3"
		)
		(pin "N4"
		)
		(pin "N5"
		)
		(pin "P1"
		)
		(pin "P2"
		)
		(pin "P4"
		)
		(pin "P5"
		)
		(pin "R1"
		)
		(pin "R2"
		)
		(pin "R3"
		)
		(pin "R4"
		)
		(pin "T1"
		)
		(pin "T3"
		)
		(pin "T4"
		)
		(pin "T5"
		)
		(pin "U1"
		)
		(pin "U2"
		)
		(pin "U3"
		)
		(pin "U5"
		)
		(pin "V2"
		)
		(pin "V3"
		)
		(pin "V4"
		)
		(pin "V5"
		)
		(pin "W1"
		)
		(pin "W2"
		)
		(pin "W4"
		)
		(pin "W5"
		)
		(pin "Y1"
		)
		(pin "Y2"
		)
		(pin "Y3"
		)
		(pin "Y4"
		)
		(pin "AA10"
		)
		(pin "AA11"
		)
		(pin "AA13"
		)
		(pin "AA5"
		)
		(pin "AA6"
		)
		(pin "AA8"
		)
		(pin "AA9"
		)
		(pin "AB10"
		)
		(pin "AB7"
		)
		(pin "AB8"
		)
		(pin "R6"
		)
		(pin "R7"
		)
		(pin "T10"
		)
		(pin "T11"
		)
		(pin "T13"
		)
		(pin "T14"
		)
		(pin "T6"
		)
		(pin "T8"
		)
		(pin "T9"
		)
		(pin "U10"
		)
		(pin "U11"
		)
		(pin "U12"
		)
		(pin "U13"
		)
		(pin "U6"
		)
		(pin "U7"
		)
		(pin "U8"
		)
		(pin "V10"
		)
		(pin "V12"
		)
		(pin "V13"
		)
		(pin "V7"
		)
		(pin "V8"
		)
		(pin "V9"
		)
		(pin "W10"
		)
		(pin "W11"
		)
		(pin "W12"
		)
		(pin "W6"
		)
		(pin "W7"
		)
		(pin "W9"
		)
		(pin "Y11"
		)
		(pin "Y12"
		)
		(pin "Y13"
		)
		(pin "Y6"
		)
		(pin "Y7"
		)
		(pin "Y8"
		)
		(pin "Y9"
		)
		(pin "A10"
		)
		(pin "A11"
		)
		(pin "A8"
		)
		(pin "A9"
		)
		(pin "B10"
		)
		(pin "B11"
		)
		(pin "B8"
		)
		(pin "C10"
		)
		(pin "C8"
		)
		(pin "C9"
		)
		(pin "D10"
		)
		(pin "D11"
		)
		(pin "D9"
		)
		(pin "E11"
		)
		(pin "E12"
		)
		(pin "E13"
		)
		(pin "E8"
		)
		(pin "E9"
		)
		(pin "F10"
		)
		(pin "F11"
		)
		(pin "F13"
		)
		(pin "F14"
		)
		(pin "F8"
		)
		(pin "F9"
		)
		(pin "G10"
		)
		(pin "G11"
		)
		(pin "G12"
		)
		(pin "G13"
		)
		(pin "G8"
		)
		(pin "H10"
		)
		(pin "H12"
		)
		(pin "H13"
		)
		(pin "H14"
		)
		(pin "H8"
		)
		(pin "H9"
		)
		(pin "A13"
		)
		(pin "A14"
		)
		(pin "A15"
		)
		(pin "A16"
		)
		(pin "A18"
		)
		(pin "A19"
		)
		(pin "A20"
		)
		(pin "A21"
		)
		(pin "B12"
		)
		(pin "B13"
		)
		(pin "B15"
		)
		(pin "B16"
		)
		(pin "B17"
		)
		(pin "B18"
		)
		(pin "B20"
		)
		(pin "B21"
		)
		(pin "B22"
		)
		(pin "C12"
		)
		(pin "C13"
		)
		(pin "C14"
		)
		(pin "C15"
		)
		(pin "C17"
		)
		(pin "C18"
		)
		(pin "C19"
		)
		(pin "C20"
		)
		(pin "C22"
		)
		(pin "D12"
		)
		(pin "D14"
		)
		(pin "D15"
		)
		(pin "D16"
		)
		(pin "D17"
		)
		(pin "D19"
		)
		(pin "D20"
		)
		(pin "D21"
		)
		(pin "D22"
		)
		(pin "E14"
		)
		(pin "E16"
		)
		(pin "E17"
		)
		(pin "E18"
		)
		(pin "E19"
		)
		(pin "F15"
		)
		(pin "F16"
		)
		(pin "F18"
		)
		(pin "G15"
		)
		(pin "G16"
		)
		(pin "G17"
		)
		(pin "H15"
		)
		(pin "H17"
		)
		(pin "J16"
		)
		(pin "J17"
		)
		(pin "AA14"
		)
		(pin "AA15"
		)
		(pin "AA16"
		)
		(pin "AA18"
		)
		(pin "AA19"
		)
		(pin "AA20"
		)
		(pin "AA21"
		)
		(pin "AB15"
		)
		(pin "AB16"
		)
		(pin "AB17"
		)
		(pin "AB18"
		)
		(pin "AB20"
		)
		(pin "AB21"
		)
		(pin "AB22"
		)
		(pin "R16"
		)
		(pin "T15"
		)
		(pin "T16"
		)
		(pin "T18"
		)
		(pin "T19"
		)
		(pin "T20"
		)
		(pin "T21"
		)
		(pin "U15"
		)
		(pin "U16"
		)
		(pin "U17"
		)
		(pin "U18"
		)
		(pin "U20"
		)
		(pin "U21"
		)
		(pin "U22"
		)
		(pin "V14"
		)
		(pin "V15"
		)
		(pin "V17"
		)
		(pin "V18"
		)
		(pin "V19"
		)
		(pin "V20"
		)
		(pin "V22"
		)
		(pin "W14"
		)
		(pin "W15"
		)
		(pin "W16"
		)
		(pin "W17"
		)
		(pin "W19"
		)
		(pin "W20"
		)
		(pin "W21"
		)
		(pin "W22"
		)
		(pin "Y14"
		)
		(pin "Y16"
		)
		(pin "Y17"
		)
		(pin "Y18"
		)
		(pin "Y19"
		)
		(pin "Y21"
		)
		(pin "Y22"
		)
		(instances
			(project "lpddr4-test-board"
				(path ""
					(reference "U3")
					(unit 8)
				)
			)
		)
	)
)
